FILE_TYPE = MACRO_DRAWING;
SET COLOR_WIRE YELLOW;
SET COLOR_PROP MONO;
SET COLOR_DOT WHITE;
SET COLOR_ARC YELLOW;
SET COLOR_BODY GREEN;
SET COLOR_NOTE MONO;
SET PROP_DISPLAY VALUE;
SET PAGE_NUMBER P130;
FORCEADD CAP_A..1
(1925 1600);
FORCEPROP 1 LAST LOCATION C2N20
J 0
(1975 1700);
DISPLAY 0.617021 (1975 1700);
PAINT AQUA (1975 1700);
FORCEPROP 1 LAST PART_NUMBER D97712-004
J 0
(1975 1450);
DISPLAY 0.617021 (1975 1450);
PAINT BLUE (1975 1450);
FORCEPROP 1 LAST VALUE 1.0UF
J 0
(1975 1650);
DISPLAY 0.617021 (1975 1650);
PAINT SKYBLUE (1975 1650);
FORCEPROP 1 LAST TOLERANCE 10%
J 0
(1975 1550);
DISPLAY 0.617021 (1975 1550);
PAINT SKYBLUE (1975 1550);
FORCEPROP 1 LAST PACK_TYPE 0402V
J 0
(1975 1400);
DISPLAY 0.617021 (1975 1400);
PAINT SKYBLUE (1975 1400);
FORCEPROP 1 LAST VOLTAGE 6.3V
J 0
(1975 1600);
DISPLAY 0.617021 (1975 1600);
PAINT SKYBLUE (1975 1600);
FORCEPROP 1 LAST MATERIAL X6S
J 0
(1975 1500);
DISPLAY 0.617021 (1975 1500);
PAINT SKYBLUE (1975 1500);
FORCEPROP 1 LASTPIN (1925 1700) $PN 1
J 0
(1935 1680);
DISPLAY 0.617021 (1935 1680);
PAINT WHITE (1935 1680);
FORCEPROP 1 LASTPIN (1925 1500) $PN 2
J 0
(1935 1480);
DISPLAY 0.617021 (1935 1480);
PAINT WHITE (1935 1480);
FORCEPROP 2 LAST CDS_LOCATION C2N20
J 0
(1975 1700);
DISPLAY 0.617021 (1975 1700);
PAINT AQUA (1975 1700);
DISPLAY INVISIBLE (1975 1700);
FORCEPROP 2 LAST BOM_COST SB
J 0
(1975 1350);
PAINT MONO (1975 1350);
DISPLAY INVISIBLE (1975 1350);
FORCEPROP 2 LAST CDS_LIB dev_discrete
J 0
(1925 1600);
PAINT ORANGE (1925 1600);
DISPLAY INVISIBLE (1925 1600);
FORCEPROP 2 LAST CDS_SEC 1
J 0
(1975 1800);
DISPLAY 1.361702 (1975 1800);
PAINT ORANGE (1975 1800);
DISPLAY INVISIBLE (1975 1800);
FORCEPROP 2 LAST $SEC 1
J 0
(1975 1800);
DISPLAY 0.914894 (1975 1800);
PAINT MONO (1975 1800);
DISPLAY INVISIBLE (1975 1800);
FORCEPROP 1 LAST PATH I12
J 0
(1975 1750);
DISPLAY 0.978723 (1975 1750);
PAINT WHITE (1975 1750);
DISPLAY INVISIBLE (1975 1750);
FORCEPROP 2 LAST ROOM SB_DECOUPLING
J 0
(1925 1600);
PAINT WHITE (1925 1600);
DISPLAY INVISIBLE (1925 1600);
FORCEADD GND..1
(1925 1300);
FORCEPROP 3 LASTPIN (1925 1350) SIG_NAME GND\g
J 0
(1935 1360);
DISPLAY 0.659574 (1935 1360);
PAINT MONO (1935 1360);
DISPLAY INVISIBLE (1935 1360);
FORCEPROP 1 LAST VOLTAGE 0
J 0
(1925 1300);
PAINT SKYBLUE (1925 1300);
DISPLAY INVISIBLE (1925 1300);
FORCEPROP 2 LAST BOM_COST SB
J 0
(1875 1375);
PAINT MONO (1875 1375);
DISPLAY INVISIBLE (1875 1375);
FORCEPROP 1 LAST SIZE 1B
J 0
(2000 1250);
DISPLAY 1.404255 (2000 1250);
PAINT GREEN (2000 1250);
DISPLAY INVISIBLE (2000 1250);
FORCEPROP 2 LAST CDS_LIB mstr_symbols
J 0
(1925 1300);
PAINT ORANGE (1925 1300);
DISPLAY INVISIBLE (1925 1300);
FORCEPROP 1 LAST BODY_TYPE PLUMBING
J 0
(1880 1257);
DISPLAY 0.340426 (1880 1257);
PAINT GREEN (1880 1257);
DISPLAY INVISIBLE (1880 1257);
FORCEPROP 1 LAST PATH I13
J 0
(2000 1300);
DISPLAY 0.872340 (2000 1300);
PAINT AQUA (2000 1300);
DISPLAY INVISIBLE (2000 1300);
FORCEPROP 2 LAST ROOM SB_DECOUPLING
J 0
(1450 1375);
PAINT WHITE (1450 1375);
DISPLAY INVISIBLE (1450 1375);
FORCEPROP 1 LAST HDL_POWER GND
J 0
(1925 1450);
DISPLAY 1.404255 (1925 1450);
PAINT GREEN (1925 1450);
DISPLAY INVISIBLE (1925 1450);
FORCEADD GND..1
(650 2350);
FORCEPROP 3 LASTPIN (650 2400) SIG_NAME GND\g
J 0
(660 2410);
DISPLAY 0.659574 (660 2410);
PAINT MONO (660 2410);
DISPLAY INVISIBLE (660 2410);
FORCEPROP 1 LAST VOLTAGE 0
J 0
(650 2350);
PAINT SKYBLUE (650 2350);
DISPLAY INVISIBLE (650 2350);
FORCEPROP 2 LAST BOM_COST SB
J 0
(600 2425);
PAINT MONO (600 2425);
DISPLAY INVISIBLE (600 2425);
FORCEPROP 2 LAST CDS_LIB mstr_symbols
J 0
(650 2350);
PAINT ORANGE (650 2350);
DISPLAY INVISIBLE (650 2350);
FORCEPROP 1 LAST SIZE 1B
J 0
(725 2300);
DISPLAY 1.404255 (725 2300);
PAINT GREEN (725 2300);
DISPLAY INVISIBLE (725 2300);
FORCEPROP 1 LAST BODY_TYPE PLUMBING
J 0
(605 2307);
DISPLAY 0.340426 (605 2307);
PAINT GREEN (605 2307);
DISPLAY INVISIBLE (605 2307);
FORCEPROP 1 LAST PATH I14
J 0
(725 2350);
DISPLAY 0.872340 (725 2350);
PAINT AQUA (725 2350);
DISPLAY INVISIBLE (725 2350);
FORCEPROP 2 LAST ROOM SB_DECOUPLING
J 0
(175 2425);
PAINT WHITE (175 2425);
DISPLAY INVISIBLE (175 2425);
FORCEPROP 1 LAST HDL_POWER GND
J 0
(650 2500);
DISPLAY 1.404255 (650 2500);
PAINT GREEN (650 2500);
DISPLAY INVISIBLE (650 2500);
FORCEADD CAP..1
(425 2650);
FORCEPROP 1 LAST LOCATION C2N21
J 0
(475 2750);
DISPLAY 0.617021 (475 2750);
PAINT AQUA (475 2750);
FORCEPROP 1 LAST PART_NUMBER E15431-002
J 0
(475 2500);
DISPLAY 0.617021 (475 2500);
PAINT BLUE (475 2500);
FORCEPROP 1 LAST VALUE 10UF
J 0
(475 2700);
DISPLAY 0.617021 (475 2700);
PAINT SKYBLUE (475 2700);
FORCEPROP 1 LAST TOLERANCE 20%
J 0
(475 2600);
DISPLAY 0.617021 (475 2600);
PAINT SKYBLUE (475 2600);
FORCEPROP 1 LAST PACK_TYPE 0603
J 0
(475 2450);
DISPLAY 0.617021 (475 2450);
PAINT SKYBLUE (475 2450);
FORCEPROP 1 LAST VOLTAGE 6.3V
J 0
(475 2650);
DISPLAY 0.617021 (475 2650);
PAINT SKYBLUE (475 2650);
FORCEPROP 1 LAST MATERIAL X6S
J 0
(475 2550);
DISPLAY 0.617021 (475 2550);
PAINT SKYBLUE (475 2550);
FORCEPROP 1 LASTPIN (425 2550) $PN 2
J 0
(435 2530);
DISPLAY 0.617021 (435 2530);
PAINT WHITE (435 2530);
FORCEPROP 1 LASTPIN (425 2750) $PN 1
J 0
(435 2730);
DISPLAY 0.617021 (435 2730);
PAINT WHITE (435 2730);
FORCEPROP 2 LAST CDS_LIB mstr_discrete
J 0
(425 2650);
PAINT ORANGE (425 2650);
DISPLAY INVISIBLE (425 2650);
FORCEPROP 2 LAST BOM_COST SB
J 0
(475 2400);
PAINT MONO (475 2400);
DISPLAY INVISIBLE (475 2400);
FORCEPROP 2 LAST CDS_SEC 1
J 0
(475 2850);
DISPLAY 1.361702 (475 2850);
PAINT ORANGE (475 2850);
DISPLAY INVISIBLE (475 2850);
FORCEPROP 2 LAST $SEC 1
J 0
(475 2850);
DISPLAY 0.914894 (475 2850);
PAINT MONO (475 2850);
DISPLAY INVISIBLE (475 2850);
FORCEPROP 2 LAST CDS_LOCATION C2N21
J 0
(475 2750);
DISPLAY 0.617021 (475 2750);
PAINT AQUA (475 2750);
DISPLAY INVISIBLE (475 2750);
FORCEPROP 1 LAST PATH I15
J 0
(475 2800);
DISPLAY 0.978723 (475 2800);
PAINT WHITE (475 2800);
DISPLAY INVISIBLE (475 2800);
FORCEPROP 2 LAST ROOM SB_DECOUPLING
J 0
(425 2650);
PAINT WHITE (425 2650);
DISPLAY INVISIBLE (425 2650);
FORCEADD CAP_A..1
R 2
(0 2025);
FORCEPROP 1 LAST LOCATION C3N29
J 2
(-50 2125);
DISPLAY 0.617021 (-50 2125);
PAINT AQUA (-50 2125);
FORCEPROP 1 LAST PART_NUMBER A36096-030
J 2
(-50 1875);
DISPLAY 0.617021 (-50 1875);
PAINT BLUE (-50 1875);
FORCEPROP 1 LAST VALUE 0.1UF
J 2
(-50 2075);
DISPLAY 0.617021 (-50 2075);
PAINT SKYBLUE (-50 2075);
FORCEPROP 1 LAST TOLERANCE 10%
J 2
(-50 1975);
DISPLAY 0.617021 (-50 1975);
PAINT SKYBLUE (-50 1975);
FORCEPROP 1 LAST PACK_TYPE 0402V
J 2
(-50 1825);
DISPLAY 0.617021 (-50 1825);
PAINT SKYBLUE (-50 1825);
FORCEPROP 1 LAST VOLTAGE 16V
J 2
(-50 2025);
DISPLAY 0.617021 (-50 2025);
PAINT SKYBLUE (-50 2025);
FORCEPROP 1 LAST MATERIAL X7R
J 2
(-50 1925);
DISPLAY 0.617021 (-50 1925);
PAINT SKYBLUE (-50 1925);
FORCEPROP 1 LASTPIN (0 2125) $PN 1
J 2
(-10 2105);
DISPLAY 0.617021 (-10 2105);
PAINT WHITE (-10 2105);
FORCEPROP 1 LASTPIN (0 1925) $PN 2
J 2
(-10 1905);
DISPLAY 0.617021 (-10 1905);
PAINT WHITE (-10 1905);
FORCEPROP 1 LAST PATH I16
J 2
(-50 2175);
DISPLAY 0.978723 (-50 2175);
PAINT WHITE (-50 2175);
DISPLAY INVISIBLE (-50 2175);
FORCEPROP 2 LAST ROOM SB_DECOUPLING
J 2
(0 2025);
PAINT WHITE (0 2025);
DISPLAY INVISIBLE (0 2025);
FORCEPROP 2 LAST CDS_LOCATION C3N29
J 2
(-50 2125);
DISPLAY 0.617021 (-50 2125);
PAINT AQUA (-50 2125);
DISPLAY INVISIBLE (-50 2125);
FORCEPROP 2 LAST BOM_COST SB
J 2
(-50 1775);
PAINT MONO (-50 1775);
DISPLAY INVISIBLE (-50 1775);
FORCEPROP 2 LAST CDS_LIB dev_discrete
J 0
(0 2025);
PAINT ORANGE (0 2025);
DISPLAY INVISIBLE (0 2025);
FORCEPROP 2 LAST CDS_SEC 1
J 2
(-50 2225);
DISPLAY 1.361702 (-50 2225);
PAINT ORANGE (-50 2225);
DISPLAY INVISIBLE (-50 2225);
FORCEPROP 2 LAST $SEC 1
J 2
(-50 2225);
DISPLAY 0.914894 (-50 2225);
PAINT MONO (-50 2225);
DISPLAY INVISIBLE (-50 2225);
FORCEADD GND..1
(0 1725);
FORCEPROP 3 LASTPIN (0 1775) SIG_NAME GND\g
J 0
(10 1785);
DISPLAY 0.659574 (10 1785);
PAINT MONO (10 1785);
DISPLAY INVISIBLE (10 1785);
FORCEPROP 1 LAST VOLTAGE 0
J 0
(0 1725);
PAINT SKYBLUE (0 1725);
DISPLAY INVISIBLE (0 1725);
FORCEPROP 2 LAST CDS_LIB mstr_symbols
J 0
(0 1725);
PAINT ORANGE (0 1725);
DISPLAY INVISIBLE (0 1725);
FORCEPROP 1 LAST SIZE 1B
J 0
(75 1675);
DISPLAY 1.404255 (75 1675);
PAINT GREEN (75 1675);
DISPLAY INVISIBLE (75 1675);
FORCEPROP 2 LAST BOM_COST SB
J 0
(-50 1800);
PAINT MONO (-50 1800);
DISPLAY INVISIBLE (-50 1800);
FORCEPROP 1 LAST BODY_TYPE PLUMBING
J 0
(-45 1682);
DISPLAY 0.340426 (-45 1682);
PAINT GREEN (-45 1682);
DISPLAY INVISIBLE (-45 1682);
FORCEPROP 1 LAST PATH I17
J 0
(75 1725);
DISPLAY 0.872340 (75 1725);
PAINT AQUA (75 1725);
DISPLAY INVISIBLE (75 1725);
FORCEPROP 2 LAST ROOM SB_DECOUPLING
J 0
(-475 1800);
PAINT WHITE (-475 1800);
DISPLAY INVISIBLE (-475 1800);
FORCEPROP 1 LAST HDL_POWER GND
J 0
(0 1875);
DISPLAY 1.404255 (0 1875);
PAINT GREEN (0 1875);
DISPLAY INVISIBLE (0 1875);
FORCEADD OFFPAGE..1
(-625 2275);
FORCEPROP 2 LAST $XR0 122 
J 0
(-877 2275);
DISPLAY 0.638298 (-877 2275);
PAINT MONO (-877 2275);
FORCEPROP 2 LAST CDS_LIB mstr_standard
J 0
(-625 2275);
PAINT ORANGE (-625 2275);
DISPLAY INVISIBLE (-625 2275);
FORCEPROP 1 LAST OFFPAGE TRUE
J 0
(-300 2150);
DISPLAY 1.170213 (-300 2150);
PAINT GREEN (-300 2150);
DISPLAY INVISIBLE (-300 2150);
FORCEPROP 1 LAST COMMENT_BODY TRUE
J 0
(-500 2175);
DISPLAY 1.170213 (-500 2175);
PAINT GREEN (-500 2175);
DISPLAY INVISIBLE (-500 2175);
FORCEPROP 2 LAST PATH I18
J 0
(-925 2325);
DISPLAY 1.021277 (-925 2325);
PAINT ORANGE (-925 2325);
DISPLAY INVISIBLE (-925 2325);
FORCEADD CAP..1
(-2550 4925);
FORCEPROP 1 LAST LOCATION C8C3
J 0
(-2500 5025);
DISPLAY 0.617021 (-2500 5025);
PAINT AQUA (-2500 5025);
FORCEPROP 1 LAST PART_NUMBER E15431-002
J 0
(-2500 4775);
DISPLAY 0.617021 (-2500 4775);
PAINT BLUE (-2500 4775);
FORCEPROP 1 LAST VALUE 10UF
J 0
(-2500 4975);
DISPLAY 0.617021 (-2500 4975);
PAINT SKYBLUE (-2500 4975);
FORCEPROP 1 LAST TOLERANCE 20%
J 0
(-2500 4875);
DISPLAY 0.617021 (-2500 4875);
PAINT SKYBLUE (-2500 4875);
FORCEPROP 1 LAST PACK_TYPE 0603
J 0
(-2500 4725);
DISPLAY 0.617021 (-2500 4725);
PAINT SKYBLUE (-2500 4725);
FORCEPROP 1 LAST VOLTAGE 6.3V
J 0
(-2500 4925);
DISPLAY 0.617021 (-2500 4925);
PAINT SKYBLUE (-2500 4925);
FORCEPROP 1 LAST MATERIAL X6S
J 0
(-2500 4825);
DISPLAY 0.617021 (-2500 4825);
PAINT SKYBLUE (-2500 4825);
FORCEPROP 2 LAST CDS_LIB mstr_discrete
J 0
(-2550 4925);
PAINT ORANGE (-2550 4925);
DISPLAY INVISIBLE (-2550 4925);
FORCEPROP 2 LAST BOM_COST SB
J 0
(-2500 4675);
PAINT MONO (-2500 4675);
DISPLAY INVISIBLE (-2500 4675);
FORCEPROP 2 LAST CDS_SEC 1
J 0
(-2500 5125);
DISPLAY 1.361702 (-2500 5125);
PAINT ORANGE (-2500 5125);
DISPLAY INVISIBLE (-2500 5125);
FORCEPROP 2 LAST $SEC 1
J 0
(-2500 5125);
DISPLAY 0.914894 (-2500 5125);
PAINT MONO (-2500 5125);
DISPLAY INVISIBLE (-2500 5125);
FORCEPROP 2 LAST CDS_LOCATION C8C3
J 0
(-2500 5025);
DISPLAY 0.617021 (-2500 5025);
PAINT AQUA (-2500 5025);
DISPLAY INVISIBLE (-2500 5025);
FORCEPROP 1 LAST PATH I19
J 0
(-2500 5075);
DISPLAY 0.978723 (-2500 5075);
PAINT WHITE (-2500 5075);
DISPLAY INVISIBLE (-2500 5075);
FORCEPROP 2 LAST ROOM SB_DECOUPLING
J 0
(-2550 4925);
PAINT WHITE (-2550 4925);
DISPLAY INVISIBLE (-2550 4925);
FORCEPROP 1 LASTPIN (-2550 4825) $PN 2
J 0
(-2540 4805);
DISPLAY 1.063830 (-2540 4805);
PAINT WHITE (-2540 4805);
DISPLAY INVISIBLE (-2540 4805);
FORCEPROP 1 LASTPIN (-2550 5025) $PN 1
J 0
(-2540 5005);
DISPLAY 1.063830 (-2540 5005);
PAINT WHITE (-2540 5005);
DISPLAY INVISIBLE (-2540 5005);
FORCEADD CAP..1
(1125 5003);
FORCEPROP 1 LAST LOCATION C7D2
J 0
(1175 5103);
DISPLAY 0.617021 (1175 5103);
PAINT AQUA (1175 5103);
FORCEPROP 1 LAST PART_NUMBER E15431-002
J 0
(1175 4853);
DISPLAY 0.617021 (1175 4853);
PAINT BLUE (1175 4853);
FORCEPROP 1 LAST VALUE 10UF
J 0
(1175 5053);
DISPLAY 0.617021 (1175 5053);
PAINT SKYBLUE (1175 5053);
FORCEPROP 1 LAST TOLERANCE 20%
J 0
(1175 4953);
DISPLAY 0.617021 (1175 4953);
PAINT SKYBLUE (1175 4953);
FORCEPROP 1 LAST PACK_TYPE 0603
J 0
(1175 4803);
DISPLAY 0.617021 (1175 4803);
PAINT SKYBLUE (1175 4803);
FORCEPROP 1 LAST VOLTAGE 6.3V
J 0
(1175 5003);
DISPLAY 0.617021 (1175 5003);
PAINT SKYBLUE (1175 5003);
FORCEPROP 1 LAST MATERIAL X6S
J 0
(1175 4903);
DISPLAY 0.617021 (1175 4903);
PAINT SKYBLUE (1175 4903);
FORCEPROP 1 LASTPIN (1125 4903) $PN 2
J 0
(1135 4883);
DISPLAY 0.617021 (1135 4883);
PAINT WHITE (1135 4883);
FORCEPROP 1 LASTPIN (1125 5103) $PN 1
J 0
(1135 5083);
DISPLAY 0.617021 (1135 5083);
PAINT WHITE (1135 5083);
FORCEPROP 2 LAST SEC_TYPE 0603
J 0
(1197 5212);
DISPLAY 1.361702 (1197 5212);
PAINT ORANGE (1197 5212);
DISPLAY INVISIBLE (1197 5212);
FORCEPROP 2 LAST BOM_COST SB
J 0
(1175 4753);
PAINT MONO (1175 4753);
DISPLAY INVISIBLE (1175 4753);
FORCEPROP 2 LAST CDS_LIB mstr_discrete
J 0
(1125 5003);
PAINT ORANGE (1125 5003);
DISPLAY INVISIBLE (1125 5003);
FORCEPROP 2 LAST SEC 1
J 0
(1197 5212);
DISPLAY 0.914894 (1197 5212);
PAINT MONO (1197 5212);
DISPLAY INVISIBLE (1197 5212);
FORCEPROP 2 LAST CDS_LOCATION C7D2
J 0
(1175 5103);
DISPLAY 0.617021 (1175 5103);
PAINT AQUA (1175 5103);
DISPLAY INVISIBLE (1175 5103);
FORCEPROP 1 LAST PATH I2
J 0
(1175 5153);
DISPLAY 0.978723 (1175 5153);
PAINT WHITE (1175 5153);
DISPLAY INVISIBLE (1175 5153);
FORCEPROP 2 LAST ROOM SB_DECOUPLING
J 0
(1125 5003);
PAINT WHITE (1125 5003);
DISPLAY INVISIBLE (1125 5003);
FORCEADD CAP..1
(-2975 4925);
FORCEPROP 1 LAST LOCATION C8C4
J 0
(-2925 5025);
DISPLAY 0.617021 (-2925 5025);
PAINT AQUA (-2925 5025);
FORCEPROP 1 LAST VALUE 10UF
J 0
(-2925 4975);
DISPLAY 0.617021 (-2925 4975);
PAINT SKYBLUE (-2925 4975);
FORCEPROP 1 LAST TOLERANCE 20%
J 0
(-2925 4875);
DISPLAY 0.617021 (-2925 4875);
PAINT SKYBLUE (-2925 4875);
FORCEPROP 1 LAST PACK_TYPE 0603
J 0
(-2925 4725);
DISPLAY 0.617021 (-2925 4725);
PAINT SKYBLUE (-2925 4725);
FORCEPROP 1 LAST VOLTAGE 6.3V
J 0
(-2925 4925);
DISPLAY 0.617021 (-2925 4925);
PAINT SKYBLUE (-2925 4925);
FORCEPROP 1 LAST MATERIAL X6S
J 0
(-2925 4825);
DISPLAY 0.617021 (-2925 4825);
PAINT SKYBLUE (-2925 4825);
FORCEPROP 1 LAST PART_NUMBER E15431-002
J 0
(-2925 4775);
DISPLAY 0.617021 (-2925 4775);
PAINT BLUE (-2925 4775);
FORCEPROP 2 LAST CDS_LIB mstr_discrete
J 0
(-2975 4925);
PAINT ORANGE (-2975 4925);
DISPLAY INVISIBLE (-2975 4925);
FORCEPROP 2 LAST BOM_COST SB
J 0
(-2925 4675);
PAINT MONO (-2925 4675);
DISPLAY INVISIBLE (-2925 4675);
FORCEPROP 2 LAST CDS_SEC 1
J 0
(-2925 5125);
DISPLAY 1.361702 (-2925 5125);
PAINT ORANGE (-2925 5125);
DISPLAY INVISIBLE (-2925 5125);
FORCEPROP 2 LAST $SEC 1
J 0
(-2925 5125);
DISPLAY 0.914894 (-2925 5125);
PAINT MONO (-2925 5125);
DISPLAY INVISIBLE (-2925 5125);
FORCEPROP 2 LAST CDS_LOCATION C8C4
J 0
(-2925 5025);
DISPLAY 0.617021 (-2925 5025);
PAINT AQUA (-2925 5025);
DISPLAY INVISIBLE (-2925 5025);
FORCEPROP 1 LAST PATH I20
J 0
(-2925 5075);
DISPLAY 0.978723 (-2925 5075);
PAINT WHITE (-2925 5075);
DISPLAY INVISIBLE (-2925 5075);
FORCEPROP 2 LAST ROOM SB_DECOUPLING
J 0
(-2975 4925);
PAINT WHITE (-2975 4925);
DISPLAY INVISIBLE (-2975 4925);
FORCEPROP 1 LASTPIN (-2975 4825) $PN 2
J 0
(-2965 4805);
DISPLAY 1.063830 (-2965 4805);
PAINT WHITE (-2965 4805);
DISPLAY INVISIBLE (-2965 4805);
FORCEPROP 1 LASTPIN (-2975 5025) $PN 1
J 0
(-2965 5005);
DISPLAY 1.063830 (-2965 5005);
PAINT WHITE (-2965 5005);
DISPLAY INVISIBLE (-2965 5005);
FORCEADD CAP..1
(-3375 4925);
FORCEPROP 1 LAST LOCATION C8C5
J 0
(-3325 5025);
DISPLAY 0.617021 (-3325 5025);
PAINT AQUA (-3325 5025);
FORCEPROP 1 LAST PART_NUMBER E15431-002
J 0
(-3325 4775);
DISPLAY 0.617021 (-3325 4775);
PAINT BLUE (-3325 4775);
FORCEPROP 1 LAST VALUE 10UF
J 0
(-3325 4975);
DISPLAY 0.617021 (-3325 4975);
PAINT SKYBLUE (-3325 4975);
FORCEPROP 1 LAST TOLERANCE 20%
J 0
(-3325 4875);
DISPLAY 0.617021 (-3325 4875);
PAINT SKYBLUE (-3325 4875);
FORCEPROP 1 LAST PACK_TYPE 0603
J 0
(-3325 4725);
DISPLAY 0.617021 (-3325 4725);
PAINT SKYBLUE (-3325 4725);
FORCEPROP 1 LAST VOLTAGE 6.3V
J 0
(-3325 4925);
DISPLAY 0.617021 (-3325 4925);
PAINT SKYBLUE (-3325 4925);
FORCEPROP 1 LAST MATERIAL X6S
J 0
(-3325 4825);
DISPLAY 0.617021 (-3325 4825);
PAINT SKYBLUE (-3325 4825);
FORCEPROP 2 LAST CDS_LIB mstr_discrete
J 0
(-3375 4925);
PAINT ORANGE (-3375 4925);
DISPLAY INVISIBLE (-3375 4925);
FORCEPROP 2 LAST BOM_COST SB
J 0
(-3325 4675);
PAINT MONO (-3325 4675);
DISPLAY INVISIBLE (-3325 4675);
FORCEPROP 2 LAST CDS_SEC 1
J 0
(-3325 5125);
DISPLAY 1.361702 (-3325 5125);
PAINT ORANGE (-3325 5125);
DISPLAY INVISIBLE (-3325 5125);
FORCEPROP 2 LAST $SEC 1
J 0
(-3325 5125);
DISPLAY 0.914894 (-3325 5125);
PAINT MONO (-3325 5125);
DISPLAY INVISIBLE (-3325 5125);
FORCEPROP 2 LAST CDS_LOCATION C8C5
J 0
(-3325 5025);
DISPLAY 0.617021 (-3325 5025);
PAINT AQUA (-3325 5025);
DISPLAY INVISIBLE (-3325 5025);
FORCEPROP 1 LAST PATH I21
J 0
(-3325 5075);
DISPLAY 0.978723 (-3325 5075);
PAINT WHITE (-3325 5075);
DISPLAY INVISIBLE (-3325 5075);
FORCEPROP 2 LAST ROOM SB_DECOUPLING
J 0
(-3375 4925);
PAINT WHITE (-3375 4925);
DISPLAY INVISIBLE (-3375 4925);
FORCEPROP 1 LASTPIN (-3375 4825) $PN 2
J 0
(-3365 4805);
DISPLAY 1.063830 (-3365 4805);
PAINT WHITE (-3365 4805);
DISPLAY INVISIBLE (-3365 4805);
FORCEPROP 1 LASTPIN (-3375 5025) $PN 1
J 0
(-3365 5005);
DISPLAY 1.063830 (-3365 5005);
PAINT WHITE (-3365 5005);
DISPLAY INVISIBLE (-3365 5005);
FORCEADD CAP..1
(-3775 4925);
FORCEPROP 1 LAST LOCATION C8C6
J 0
(-3725 5025);
DISPLAY 0.617021 (-3725 5025);
PAINT AQUA (-3725 5025);
FORCEPROP 1 LAST PART_NUMBER E15431-002
J 0
(-3725 4775);
DISPLAY 0.617021 (-3725 4775);
PAINT BLUE (-3725 4775);
FORCEPROP 1 LAST VALUE 10UF
J 0
(-3725 4975);
DISPLAY 0.617021 (-3725 4975);
PAINT SKYBLUE (-3725 4975);
FORCEPROP 1 LAST TOLERANCE 20%
J 0
(-3725 4875);
DISPLAY 0.617021 (-3725 4875);
PAINT SKYBLUE (-3725 4875);
FORCEPROP 1 LAST PACK_TYPE 0603
J 0
(-3725 4725);
DISPLAY 0.617021 (-3725 4725);
PAINT SKYBLUE (-3725 4725);
FORCEPROP 1 LASTPIN (-3775 4825) $PN 2
J 0
(-3765 4805);
DISPLAY 0.617021 (-3765 4805);
PAINT WHITE (-3765 4805);
FORCEPROP 1 LASTPIN (-3775 5025) $PN 1
J 0
(-3765 5005);
DISPLAY 0.617021 (-3765 5005);
PAINT WHITE (-3765 5005);
FORCEPROP 1 LAST MATERIAL X6S
J 0
(-3725 4825);
DISPLAY 0.617021 (-3725 4825);
PAINT SKYBLUE (-3725 4825);
FORCEPROP 1 LAST VOLTAGE 6.3V
J 0
(-3725 4925);
PAINT SKYBLUE (-3725 4925);
DISPLAY INVISIBLE (-3725 4925);
FORCEPROP 2 LAST CDS_LIB mstr_discrete
J 0
(-3775 4925);
PAINT ORANGE (-3775 4925);
DISPLAY INVISIBLE (-3775 4925);
FORCEPROP 2 LAST BOM_COST SB
J 0
(-3725 4675);
PAINT MONO (-3725 4675);
DISPLAY INVISIBLE (-3725 4675);
FORCEPROP 2 LAST CDS_SEC 1
J 0
(-3725 5125);
DISPLAY 1.361702 (-3725 5125);
PAINT ORANGE (-3725 5125);
DISPLAY INVISIBLE (-3725 5125);
FORCEPROP 2 LAST $SEC 1
J 0
(-3725 5125);
DISPLAY 0.914894 (-3725 5125);
PAINT MONO (-3725 5125);
DISPLAY INVISIBLE (-3725 5125);
FORCEPROP 2 LAST CDS_LOCATION C8C6
J 0
(-3725 5025);
DISPLAY 0.617021 (-3725 5025);
PAINT AQUA (-3725 5025);
DISPLAY INVISIBLE (-3725 5025);
FORCEPROP 1 LAST PATH I22
J 0
(-3725 5075);
DISPLAY 0.978723 (-3725 5075);
PAINT WHITE (-3725 5075);
DISPLAY INVISIBLE (-3725 5075);
FORCEPROP 2 LAST ROOM SB_DECOUPLING
J 0
(-3775 4925);
PAINT WHITE (-3775 4925);
DISPLAY INVISIBLE (-3775 4925);
FORCEADD CAP..1
(-4175 4925);
FORCEPROP 1 LAST LOCATION C2N23
J 0
(-4125 5025);
DISPLAY 0.617021 (-4125 5025);
PAINT AQUA (-4125 5025);
FORCEPROP 1 LAST PART_NUMBER E15431-002
J 0
(-4125 4775);
DISPLAY 0.617021 (-4125 4775);
PAINT BLUE (-4125 4775);
FORCEPROP 1 LAST VALUE 10UF
J 0
(-4125 4975);
DISPLAY 0.617021 (-4125 4975);
PAINT SKYBLUE (-4125 4975);
FORCEPROP 1 LAST TOLERANCE 20%
J 0
(-4125 4875);
DISPLAY 0.617021 (-4125 4875);
PAINT SKYBLUE (-4125 4875);
FORCEPROP 1 LAST PACK_TYPE 0603
J 0
(-4125 4725);
DISPLAY 0.617021 (-4125 4725);
PAINT SKYBLUE (-4125 4725);
FORCEPROP 1 LAST VOLTAGE 6.3V
J 0
(-4125 4925);
DISPLAY 0.617021 (-4125 4925);
PAINT SKYBLUE (-4125 4925);
FORCEPROP 1 LAST MATERIAL X6S
J 0
(-4125 4825);
DISPLAY 0.617021 (-4125 4825);
PAINT SKYBLUE (-4125 4825);
FORCEPROP 2 LAST CDS_LIB mstr_discrete
J 0
(-4175 4925);
PAINT ORANGE (-4175 4925);
DISPLAY INVISIBLE (-4175 4925);
FORCEPROP 2 LAST BOM_COST SB
J 0
(-4125 4675);
PAINT MONO (-4125 4675);
DISPLAY INVISIBLE (-4125 4675);
FORCEPROP 2 LAST CDS_SEC 1
J 0
(-4125 5125);
DISPLAY 1.361702 (-4125 5125);
PAINT ORANGE (-4125 5125);
DISPLAY INVISIBLE (-4125 5125);
FORCEPROP 2 LAST $SEC 1
J 0
(-4125 5125);
DISPLAY 0.914894 (-4125 5125);
PAINT MONO (-4125 5125);
DISPLAY INVISIBLE (-4125 5125);
FORCEPROP 2 LAST CDS_LOCATION C2N23
J 0
(-4125 5025);
DISPLAY 0.617021 (-4125 5025);
PAINT AQUA (-4125 5025);
DISPLAY INVISIBLE (-4125 5025);
FORCEPROP 1 LAST PATH I24
J 0
(-4125 5075);
DISPLAY 0.978723 (-4125 5075);
PAINT WHITE (-4125 5075);
DISPLAY INVISIBLE (-4125 5075);
FORCEPROP 2 LAST ROOM SB_DECOUPLING
J 0
(-4175 4925);
PAINT WHITE (-4175 4925);
DISPLAY INVISIBLE (-4175 4925);
FORCEPROP 1 LASTPIN (-4175 4825) $PN 2
J 0
(-4165 4805);
DISPLAY 1.063830 (-4165 4805);
PAINT WHITE (-4165 4805);
DISPLAY INVISIBLE (-4165 4805);
FORCEPROP 1 LASTPIN (-4175 5025) $PN 1
J 0
(-4165 5005);
DISPLAY 1.063830 (-4165 5005);
PAINT WHITE (-4165 5005);
DISPLAY INVISIBLE (-4165 5005);
FORCEADD CAP..1
(-4575 4925);
FORCEPROP 1 LAST LOCATION C2N14
J 0
(-4525 5025);
DISPLAY 0.617021 (-4525 5025);
PAINT AQUA (-4525 5025);
FORCEPROP 1 LAST PART_NUMBER E15431-002
J 0
(-4525 4775);
DISPLAY 0.617021 (-4525 4775);
PAINT BLUE (-4525 4775);
FORCEPROP 1 LAST TOLERANCE 20%
J 0
(-4525 4875);
DISPLAY 0.617021 (-4525 4875);
PAINT SKYBLUE (-4525 4875);
FORCEPROP 1 LAST PACK_TYPE 0603
J 0
(-4525 4725);
DISPLAY 0.617021 (-4525 4725);
PAINT SKYBLUE (-4525 4725);
FORCEPROP 1 LAST MATERIAL X6S
J 0
(-4525 4825);
DISPLAY 0.617021 (-4525 4825);
PAINT SKYBLUE (-4525 4825);
FORCEPROP 1 LASTPIN (-4575 4825) $PN 2
J 0
(-4565 4805);
DISPLAY 0.617021 (-4565 4805);
PAINT WHITE (-4565 4805);
FORCEPROP 1 LASTPIN (-4575 5025) $PN 1
J 0
(-4565 5005);
DISPLAY 0.617021 (-4565 5005);
PAINT WHITE (-4565 5005);
FORCEPROP 1 LAST VALUE 10UF
J 0
(-4525 4975);
DISPLAY 0.617021 (-4525 4975);
PAINT SKYBLUE (-4525 4975);
FORCEPROP 1 LAST VOLTAGE 6.3V
J 0
(-4525 4925);
PAINT SKYBLUE (-4525 4925);
DISPLAY INVISIBLE (-4525 4925);
FORCEPROP 2 LAST CDS_LIB mstr_discrete
J 0
(-4575 4925);
PAINT ORANGE (-4575 4925);
DISPLAY INVISIBLE (-4575 4925);
FORCEPROP 2 LAST BOM_COST SB
J 0
(-4525 4675);
PAINT MONO (-4525 4675);
DISPLAY INVISIBLE (-4525 4675);
FORCEPROP 2 LAST CDS_SEC 1
J 0
(-4525 5125);
DISPLAY 1.361702 (-4525 5125);
PAINT ORANGE (-4525 5125);
DISPLAY INVISIBLE (-4525 5125);
FORCEPROP 2 LAST $SEC 1
J 0
(-4525 5125);
DISPLAY 0.914894 (-4525 5125);
PAINT MONO (-4525 5125);
DISPLAY INVISIBLE (-4525 5125);
FORCEPROP 2 LAST CDS_LOCATION C2N14
J 0
(-4525 5025);
DISPLAY 0.617021 (-4525 5025);
PAINT AQUA (-4525 5025);
DISPLAY INVISIBLE (-4525 5025);
FORCEPROP 1 LAST PATH I25
J 0
(-4525 5075);
DISPLAY 0.978723 (-4525 5075);
PAINT WHITE (-4525 5075);
DISPLAY INVISIBLE (-4525 5075);
FORCEPROP 2 LAST ROOM SB_DECOUPLING
J 0
(-4575 4925);
PAINT WHITE (-4575 4925);
DISPLAY INVISIBLE (-4575 4925);
FORCEADD GND..1
(-1475 3625);
FORCEPROP 3 LASTPIN (-1475 3675) SIG_NAME GND\g
J 0
(-1465 3685);
DISPLAY 0.659574 (-1465 3685);
PAINT MONO (-1465 3685);
DISPLAY INVISIBLE (-1465 3685);
FORCEPROP 1 LAST VOLTAGE 0.0V
J 0
(-1520 3582);
DISPLAY 0.340426 (-1520 3582);
PAINT SKYBLUE (-1520 3582);
DISPLAY INVISIBLE (-1520 3582);
FORCEPROP 2 LAST CDS_LIB mstr_symbols
J 0
(-1475 3625);
PAINT MONO (-1475 3625);
DISPLAY INVISIBLE (-1475 3625);
FORCEPROP 1 LAST SIZE 1B
J 0
(-1400 3575);
DISPLAY 1.170213 (-1400 3575);
PAINT AQUA (-1400 3575);
DISPLAY INVISIBLE (-1400 3575);
FORCEPROP 2 LAST BOM_COST SB
J 0
(-1450 3700);
DISPLAY 1.361702 (-1450 3700);
PAINT ORANGE (-1450 3700);
DISPLAY INVISIBLE (-1450 3700);
FORCEPROP 1 LAST BODY_TYPE PLUMBING
J 0
(-1520 3582);
DISPLAY 0.340426 (-1520 3582);
PAINT GREEN (-1520 3582);
DISPLAY INVISIBLE (-1520 3582);
FORCEPROP 1 LAST PATH I27
J 0
(-1400 3625);
DISPLAY 0.872340 (-1400 3625);
PAINT AQUA (-1400 3625);
DISPLAY INVISIBLE (-1400 3625);
FORCEPROP 2 LAST ROOM SB_DECOUPLING
J 0
(-1450 3700);
DISPLAY 1.361702 (-1450 3700);
PAINT ORANGE (-1450 3700);
DISPLAY INVISIBLE (-1450 3700);
FORCEPROP 1 LAST HDL_POWER GND
J 0
(-1475 3775);
DISPLAY 1.170213 (-1475 3775);
PAINT GREEN (-1475 3775);
DISPLAY INVISIBLE (-1475 3775);
FORCEADD CAP..1
(-1475 3925);
FORCEPROP 1 LAST LOCATION C2N17
J 0
(-1425 4025);
DISPLAY 0.617021 (-1425 4025);
PAINT AQUA (-1425 4025);
FORCEPROP 1 LAST PART_NUMBER E15431-002
J 0
(-1425 3775);
DISPLAY 0.617021 (-1425 3775);
PAINT BLUE (-1425 3775);
FORCEPROP 1 LAST VALUE 10UF
J 0
(-1425 3975);
DISPLAY 0.617021 (-1425 3975);
PAINT SKYBLUE (-1425 3975);
FORCEPROP 1 LAST TOLERANCE 20%
J 0
(-1425 3875);
DISPLAY 0.617021 (-1425 3875);
PAINT SKYBLUE (-1425 3875);
FORCEPROP 1 LAST PACK_TYPE 0603
J 0
(-1425 3725);
DISPLAY 0.617021 (-1425 3725);
PAINT SKYBLUE (-1425 3725);
FORCEPROP 1 LAST VOLTAGE 6.3V
J 0
(-1425 3925);
DISPLAY 0.617021 (-1425 3925);
PAINT SKYBLUE (-1425 3925);
FORCEPROP 1 LAST MATERIAL X6S
J 0
(-1425 3825);
DISPLAY 0.617021 (-1425 3825);
PAINT SKYBLUE (-1425 3825);
FORCEPROP 1 LASTPIN (-1475 3825) $PN 2
J 0
(-1465 3805);
DISPLAY 0.617021 (-1465 3805);
PAINT WHITE (-1465 3805);
FORCEPROP 1 LASTPIN (-1475 4025) $PN 1
J 0
(-1465 4005);
DISPLAY 0.617021 (-1465 4005);
PAINT WHITE (-1465 4005);
FORCEPROP 2 LAST CDS_LIB mstr_discrete
J 0
(-1475 3925);
PAINT MONO (-1475 3925);
DISPLAY INVISIBLE (-1475 3925);
FORCEPROP 2 LAST BOM_COST SB
J 0
(-1425 4125);
DISPLAY 1.361702 (-1425 4125);
PAINT ORANGE (-1425 4125);
DISPLAY INVISIBLE (-1425 4125);
FORCEPROP 2 LAST CDS_SEC 1
J 0
(-1425 4125);
DISPLAY 1.361702 (-1425 4125);
PAINT ORANGE (-1425 4125);
DISPLAY INVISIBLE (-1425 4125);
FORCEPROP 2 LAST $SEC 1
J 0
(-1425 4125);
DISPLAY 0.914894 (-1425 4125);
PAINT MONO (-1425 4125);
DISPLAY INVISIBLE (-1425 4125);
FORCEPROP 2 LAST CDS_LOCATION C2N17
J 0
(-1425 4025);
DISPLAY 0.617021 (-1425 4025);
PAINT AQUA (-1425 4025);
DISPLAY INVISIBLE (-1425 4025);
FORCEPROP 1 LAST PATH I28
J 0
(-1425 4075);
DISPLAY 0.978723 (-1425 4075);
PAINT WHITE (-1425 4075);
DISPLAY INVISIBLE (-1425 4075);
FORCEPROP 2 LAST ROOM SB_DECOUPLING
J 0
(-1425 4075);
DISPLAY 1.361702 (-1425 4075);
PAINT ORANGE (-1425 4075);
DISPLAY INVISIBLE (-1425 4075);
FORCEADD CAP_A..1
(-3450 3925);
FORCEPROP 1 LAST LOCATION C2N18
J 0
(-3400 4025);
DISPLAY 0.617021 (-3400 4025);
PAINT AQUA (-3400 4025);
FORCEPROP 1 LAST PART_NUMBER D97712-004
J 0
(-3400 3775);
DISPLAY 0.617021 (-3400 3775);
PAINT BLUE (-3400 3775);
FORCEPROP 1 LAST VALUE 1.0UF
J 0
(-3400 3975);
DISPLAY 0.617021 (-3400 3975);
PAINT SKYBLUE (-3400 3975);
FORCEPROP 1 LAST TOLERANCE 10%
J 0
(-3400 3875);
DISPLAY 0.617021 (-3400 3875);
PAINT SKYBLUE (-3400 3875);
FORCEPROP 1 LAST PACK_TYPE 0402V
J 0
(-3400 3725);
DISPLAY 0.617021 (-3400 3725);
PAINT SKYBLUE (-3400 3725);
FORCEPROP 1 LAST VOLTAGE 6.3V
J 0
(-3400 3925);
DISPLAY 0.617021 (-3400 3925);
PAINT SKYBLUE (-3400 3925);
FORCEPROP 1 LAST MATERIAL X6S
J 0
(-3400 3825);
DISPLAY 0.617021 (-3400 3825);
PAINT SKYBLUE (-3400 3825);
FORCEPROP 1 LASTPIN (-3450 4025) $PN 1
J 0
(-3440 4005);
DISPLAY 0.617021 (-3440 4005);
PAINT WHITE (-3440 4005);
FORCEPROP 1 LASTPIN (-3450 3825) $PN 2
J 0
(-3440 3805);
DISPLAY 0.617021 (-3440 3805);
PAINT WHITE (-3440 3805);
FORCEPROP 2 LAST CDS_LOCATION C2N18
J 0
(-3400 4025);
DISPLAY 0.617021 (-3400 4025);
PAINT AQUA (-3400 4025);
DISPLAY INVISIBLE (-3400 4025);
FORCEPROP 2 LAST BOM_COST SB
J 0
(-3400 3675);
PAINT MONO (-3400 3675);
DISPLAY INVISIBLE (-3400 3675);
FORCEPROP 2 LAST CDS_LIB dev_discrete
J 0
(-3450 3925);
PAINT ORANGE (-3450 3925);
DISPLAY INVISIBLE (-3450 3925);
FORCEPROP 2 LAST CDS_SEC 1
J 0
(-3400 4125);
DISPLAY 1.361702 (-3400 4125);
PAINT ORANGE (-3400 4125);
DISPLAY INVISIBLE (-3400 4125);
FORCEPROP 2 LAST $SEC 1
J 0
(-3400 4125);
DISPLAY 0.914894 (-3400 4125);
PAINT MONO (-3400 4125);
DISPLAY INVISIBLE (-3400 4125);
FORCEPROP 1 LAST PATH I29
J 0
(-3400 4075);
DISPLAY 0.978723 (-3400 4075);
PAINT WHITE (-3400 4075);
DISPLAY INVISIBLE (-3400 4075);
FORCEPROP 2 LAST ROOM SB_DECOUPLING
J 0
(-3450 3925);
PAINT WHITE (-3450 3925);
DISPLAY INVISIBLE (-3450 3925);
FORCEADD GND..1
(1125 4725);
FORCEPROP 3 LASTPIN (1125 4775) SIG_NAME GND\g
J 0
(1135 4785);
DISPLAY 0.659574 (1135 4785);
PAINT MONO (1135 4785);
DISPLAY INVISIBLE (1135 4785);
FORCEPROP 1 LAST VOLTAGE 0
J 0
(1125 4725);
PAINT SKYBLUE (1125 4725);
DISPLAY INVISIBLE (1125 4725);
FORCEPROP 2 LAST BOM_COST SB
J 0
(1075 4800);
PAINT MONO (1075 4800);
DISPLAY INVISIBLE (1075 4800);
FORCEPROP 1 LAST SIZE 1B
J 0
(1200 4675);
DISPLAY 1.404255 (1200 4675);
PAINT GREEN (1200 4675);
DISPLAY INVISIBLE (1200 4675);
FORCEPROP 2 LAST CDS_LIB mstr_symbols
J 0
(1125 4725);
PAINT ORANGE (1125 4725);
DISPLAY INVISIBLE (1125 4725);
FORCEPROP 1 LAST BODY_TYPE PLUMBING
J 0
(1080 4682);
DISPLAY 0.340426 (1080 4682);
PAINT GREEN (1080 4682);
DISPLAY INVISIBLE (1080 4682);
FORCEPROP 1 LAST PATH I3
J 0
(1200 4725);
DISPLAY 0.872340 (1200 4725);
PAINT AQUA (1200 4725);
DISPLAY INVISIBLE (1200 4725);
FORCEPROP 2 LAST ROOM SB_DECOUPLING
J 0
(650 4800);
PAINT WHITE (650 4800);
DISPLAY INVISIBLE (650 4800);
FORCEPROP 1 LAST HDL_POWER GND
J 0
(1125 4875);
DISPLAY 1.404255 (1125 4875);
PAINT GREEN (1125 4875);
DISPLAY INVISIBLE (1125 4875);
FORCEADD CAP_A..1
(-3100 2750);
FORCEPROP 1 LAST LOCATION C8B2
J 0
(-3050 2850);
DISPLAY 0.617021 (-3050 2850);
PAINT AQUA (-3050 2850);
FORCEPROP 1 LAST PART_NUMBER E15431-004
J 0
(-3050 2600);
DISPLAY 0.617021 (-3050 2600);
PAINT BLUE (-3050 2600);
FORCEPROP 1 LAST VALUE 22.0UF
J 0
(-3050 2800);
DISPLAY 0.617021 (-3050 2800);
PAINT SKYBLUE (-3050 2800);
FORCEPROP 1 LAST TOLERANCE 20%
J 0
(-3050 2700);
DISPLAY 0.617021 (-3050 2700);
PAINT SKYBLUE (-3050 2700);
FORCEPROP 1 LAST PACK_TYPE 0603V
J 0
(-3050 2550);
DISPLAY 0.617021 (-3050 2550);
PAINT SKYBLUE (-3050 2550);
FORCEPROP 1 LAST VOLTAGE 4V
J 0
(-3050 2750);
DISPLAY 0.617021 (-3050 2750);
PAINT SKYBLUE (-3050 2750);
FORCEPROP 1 LAST MATERIAL X6S
J 0
(-3050 2650);
DISPLAY 0.617021 (-3050 2650);
PAINT SKYBLUE (-3050 2650);
FORCEPROP 2 LAST CDS_LOCATION C8B2
J 0
(-3050 2850);
DISPLAY 0.617021 (-3050 2850);
PAINT AQUA (-3050 2850);
DISPLAY INVISIBLE (-3050 2850);
FORCEPROP 2 LAST BOM_COST SB
J 0
(-3050 2500);
PAINT MONO (-3050 2500);
DISPLAY INVISIBLE (-3050 2500);
FORCEPROP 2 LAST CDS_LIB dev_discrete
J 0
(-3100 2750);
PAINT ORANGE (-3100 2750);
DISPLAY INVISIBLE (-3100 2750);
FORCEPROP 2 LAST CDS_SEC 1
J 0
(-3050 2950);
DISPLAY 1.361702 (-3050 2950);
PAINT ORANGE (-3050 2950);
DISPLAY INVISIBLE (-3050 2950);
FORCEPROP 2 LAST $SEC 1
J 0
(-3050 2950);
DISPLAY 0.914894 (-3050 2950);
PAINT MONO (-3050 2950);
DISPLAY INVISIBLE (-3050 2950);
FORCEPROP 1 LAST PATH I30
J 0
(-3050 2900);
DISPLAY 0.978723 (-3050 2900);
PAINT WHITE (-3050 2900);
DISPLAY INVISIBLE (-3050 2900);
FORCEPROP 2 LAST ROOM SB_DECOUPLING
J 0
(-3100 2750);
PAINT WHITE (-3100 2750);
DISPLAY INVISIBLE (-3100 2750);
FORCEPROP 1 LASTPIN (-3100 2850) $PN 1
J 0
(-3090 2830);
DISPLAY 1.063830 (-3090 2830);
PAINT WHITE (-3090 2830);
DISPLAY INVISIBLE (-3090 2830);
FORCEPROP 1 LASTPIN (-3100 2650) $PN 2
J 0
(-3090 2630);
DISPLAY 1.063830 (-3090 2630);
PAINT WHITE (-3090 2630);
DISPLAY INVISIBLE (-3090 2630);
FORCEADD P1V8_PCH_STBY..1
(-1975 2175);
FORCEPROP 3 LASTPIN (-1975 2125) SIG_NAME P1V8_PCH_STBY\g
J 0
(-1965 2135);
DISPLAY 0.659574 (-1965 2135);
PAINT MONO (-1965 2135);
DISPLAY INVISIBLE (-1965 2135);
FORCEPROP 1 LAST VOLTAGE 1.8V
J 0
(-2020 2132);
DISPLAY 0.340426 (-2020 2132);
PAINT SKYBLUE (-2020 2132);
DISPLAY INVISIBLE (-2020 2132);
FORCEPROP 2 LAST BOM_COST SB
J 0
(-1975 2325);
PAINT MONO (-1975 2325);
DISPLAY INVISIBLE (-1975 2325);
FORCEPROP 2 LAST CDS_LIB mstr_symbols
J 0
(-1975 2175);
PAINT ORANGE (-1975 2175);
DISPLAY INVISIBLE (-1975 2175);
FORCEPROP 1 LAST BODY_TYPE PLUMBING
J 0
(-2020 2132);
DISPLAY 0.340426 (-2020 2132);
PAINT GREEN (-2020 2132);
DISPLAY INVISIBLE (-2020 2132);
FORCEPROP 1 LAST PATH I31
J 0
(-1925 2200);
DISPLAY 0.872340 (-1925 2200);
PAINT AQUA (-1925 2200);
DISPLAY INVISIBLE (-1925 2200);
FORCEPROP 2 LAST ROOM SB_DECOUPLING
J 0
(-1975 2275);
DISPLAY 1.361702 (-1975 2275);
PAINT WHITE (-1975 2275);
DISPLAY INVISIBLE (-1975 2275);
FORCEPROP 1 LAST HDL_POWER P1V8_PCH_STBY
J 1
(-1975 2225);
DISPLAY 0.872340 (-1975 2225);
PAINT GREEN (-1975 2225);
DISPLAY INVISIBLE (-1975 2225);
FORCEADD CAP_A..1
(-1975 1900);
FORCEPROP 1 LAST LOCATION C8B3
J 0
(-1925 2000);
DISPLAY 0.617021 (-1925 2000);
PAINT AQUA (-1925 2000);
FORCEPROP 1 LAST PART_NUMBER E15431-004
J 0
(-1925 1750);
DISPLAY 0.617021 (-1925 1750);
PAINT BLUE (-1925 1750);
FORCEPROP 1 LAST VALUE 22.0UF
J 0
(-1925 1950);
DISPLAY 0.617021 (-1925 1950);
PAINT SKYBLUE (-1925 1950);
FORCEPROP 1 LAST TOLERANCE 20%
J 0
(-1925 1850);
DISPLAY 0.617021 (-1925 1850);
PAINT SKYBLUE (-1925 1850);
FORCEPROP 1 LAST PACK_TYPE 0603V
J 0
(-1925 1700);
DISPLAY 0.617021 (-1925 1700);
PAINT SKYBLUE (-1925 1700);
FORCEPROP 1 LAST VOLTAGE 4V
J 0
(-1925 1900);
DISPLAY 0.617021 (-1925 1900);
PAINT SKYBLUE (-1925 1900);
FORCEPROP 1 LAST MATERIAL X6S
J 0
(-1925 1800);
DISPLAY 0.617021 (-1925 1800);
PAINT SKYBLUE (-1925 1800);
FORCEPROP 1 LASTPIN (-1975 2000) $PN 1
J 0
(-1965 1980);
DISPLAY 0.617021 (-1965 1980);
PAINT WHITE (-1965 1980);
FORCEPROP 1 LASTPIN (-1975 1800) $PN 2
J 0
(-1965 1780);
DISPLAY 0.617021 (-1965 1780);
PAINT WHITE (-1965 1780);
FORCEPROP 2 LAST CDS_LOCATION C8B3
J 0
(-1925 2000);
DISPLAY 0.617021 (-1925 2000);
PAINT AQUA (-1925 2000);
DISPLAY INVISIBLE (-1925 2000);
FORCEPROP 2 LAST BOM_COST SB
J 0
(-1925 2100);
DISPLAY 1.361702 (-1925 2100);
PAINT ORANGE (-1925 2100);
DISPLAY INVISIBLE (-1925 2100);
FORCEPROP 2 LAST CDS_LIB dev_discrete
J 0
(-1975 1900);
PAINT ORANGE (-1975 1900);
DISPLAY INVISIBLE (-1975 1900);
FORCEPROP 2 LAST CDS_SEC 1
J 0
(-1925 2100);
DISPLAY 1.361702 (-1925 2100);
PAINT ORANGE (-1925 2100);
DISPLAY INVISIBLE (-1925 2100);
FORCEPROP 2 LAST $SEC 1
J 0
(-1925 2100);
DISPLAY 0.914894 (-1925 2100);
PAINT MONO (-1925 2100);
DISPLAY INVISIBLE (-1925 2100);
FORCEPROP 1 LAST PATH I32
J 0
(-1925 2050);
DISPLAY 0.978723 (-1925 2050);
PAINT WHITE (-1925 2050);
DISPLAY INVISIBLE (-1925 2050);
FORCEPROP 2 LAST ROOM SB_DECOUPLING
J 0
(-1925 2050);
DISPLAY 1.361702 (-1925 2050);
PAINT ORANGE (-1925 2050);
DISPLAY INVISIBLE (-1925 2050);
FORCEADD GND..1
(-1975 1575);
FORCEPROP 3 LASTPIN (-1975 1625) SIG_NAME GND\g
J 0
(-1965 1635);
DISPLAY 0.659574 (-1965 1635);
PAINT MONO (-1965 1635);
DISPLAY INVISIBLE (-1965 1635);
FORCEPROP 1 LAST VOLTAGE 0.0V
J 0
(-2020 1532);
DISPLAY 0.340426 (-2020 1532);
PAINT SKYBLUE (-2020 1532);
DISPLAY INVISIBLE (-2020 1532);
FORCEPROP 2 LAST CDS_LIB mstr_symbols
J 0
(-1975 1575);
PAINT MONO (-1975 1575);
DISPLAY INVISIBLE (-1975 1575);
FORCEPROP 1 LAST SIZE 1B
J 0
(-1900 1525);
DISPLAY 1.170213 (-1900 1525);
PAINT AQUA (-1900 1525);
DISPLAY INVISIBLE (-1900 1525);
FORCEPROP 2 LAST BOM_COST SB
J 0
(-1950 1650);
DISPLAY 1.361702 (-1950 1650);
PAINT ORANGE (-1950 1650);
DISPLAY INVISIBLE (-1950 1650);
FORCEPROP 1 LAST BODY_TYPE PLUMBING
J 0
(-2020 1532);
DISPLAY 0.340426 (-2020 1532);
PAINT GREEN (-2020 1532);
DISPLAY INVISIBLE (-2020 1532);
FORCEPROP 1 LAST PATH I33
J 0
(-1900 1575);
DISPLAY 0.872340 (-1900 1575);
PAINT AQUA (-1900 1575);
DISPLAY INVISIBLE (-1900 1575);
FORCEPROP 2 LAST ROOM SB_DECOUPLING
J 0
(-1950 1650);
DISPLAY 1.361702 (-1950 1650);
PAINT ORANGE (-1950 1650);
DISPLAY INVISIBLE (-1950 1650);
FORCEPROP 1 LAST HDL_POWER GND
J 0
(-1975 1725);
DISPLAY 1.170213 (-1975 1725);
PAINT GREEN (-1975 1725);
DISPLAY INVISIBLE (-1975 1725);
FORCEADD CAP_A..1
(-3825 3925);
FORCEPROP 1 LAST LOCATION C2N25
J 0
(-3775 4025);
DISPLAY 0.617021 (-3775 4025);
PAINT AQUA (-3775 4025);
FORCEPROP 1 LAST PART_NUMBER D97712-004
J 0
(-3775 3775);
DISPLAY 0.617021 (-3775 3775);
PAINT BLUE (-3775 3775);
FORCEPROP 1 LAST VALUE 1.0UF
J 0
(-3775 3975);
DISPLAY 0.617021 (-3775 3975);
PAINT SKYBLUE (-3775 3975);
FORCEPROP 1 LAST TOLERANCE 10%
J 0
(-3775 3875);
DISPLAY 0.617021 (-3775 3875);
PAINT SKYBLUE (-3775 3875);
FORCEPROP 1 LAST PACK_TYPE 0402V
J 0
(-3775 3725);
DISPLAY 0.617021 (-3775 3725);
PAINT SKYBLUE (-3775 3725);
FORCEPROP 1 LAST VOLTAGE 6.3V
J 0
(-3775 3925);
DISPLAY 0.617021 (-3775 3925);
PAINT SKYBLUE (-3775 3925);
FORCEPROP 1 LAST MATERIAL X6S
J 0
(-3775 3825);
DISPLAY 0.617021 (-3775 3825);
PAINT SKYBLUE (-3775 3825);
FORCEPROP 1 LASTPIN (-3825 4025) $PN 1
J 0
(-3815 4005);
DISPLAY 0.617021 (-3815 4005);
PAINT WHITE (-3815 4005);
FORCEPROP 1 LASTPIN (-3825 3825) $PN 2
J 0
(-3815 3805);
DISPLAY 0.617021 (-3815 3805);
PAINT WHITE (-3815 3805);
FORCEPROP 2 LAST CDS_LOCATION C2N25
J 0
(-3775 4025);
DISPLAY 0.617021 (-3775 4025);
PAINT AQUA (-3775 4025);
DISPLAY INVISIBLE (-3775 4025);
FORCEPROP 2 LAST BOM_COST SB
J 0
(-3775 3675);
PAINT MONO (-3775 3675);
DISPLAY INVISIBLE (-3775 3675);
FORCEPROP 2 LAST CDS_LIB dev_discrete
J 0
(-3825 3925);
PAINT ORANGE (-3825 3925);
DISPLAY INVISIBLE (-3825 3925);
FORCEPROP 2 LAST CDS_SEC 1
J 0
(-3775 4125);
DISPLAY 1.361702 (-3775 4125);
PAINT ORANGE (-3775 4125);
DISPLAY INVISIBLE (-3775 4125);
FORCEPROP 2 LAST $SEC 1
J 0
(-3775 4125);
DISPLAY 0.914894 (-3775 4125);
PAINT MONO (-3775 4125);
DISPLAY INVISIBLE (-3775 4125);
FORCEPROP 1 LAST PATH I34
J 0
(-3775 4075);
DISPLAY 0.978723 (-3775 4075);
PAINT WHITE (-3775 4075);
DISPLAY INVISIBLE (-3775 4075);
FORCEPROP 2 LAST ROOM SB_DECOUPLING
J 0
(-3825 3925);
PAINT WHITE (-3825 3925);
DISPLAY INVISIBLE (-3825 3925);
FORCEADD GND..1
(-4325 4575);
FORCEPROP 3 LASTPIN (-4325 4625) SIG_NAME GND\g
J 0
(-4315 4635);
DISPLAY 0.659574 (-4315 4635);
PAINT MONO (-4315 4635);
DISPLAY INVISIBLE (-4315 4635);
FORCEPROP 1 LAST VOLTAGE 0
J 0
(-4325 4575);
PAINT SKYBLUE (-4325 4575);
DISPLAY INVISIBLE (-4325 4575);
FORCEPROP 2 LAST BOM_COST SB
J 0
(-4375 4650);
PAINT MONO (-4375 4650);
DISPLAY INVISIBLE (-4375 4650);
FORCEPROP 2 LAST CDS_LIB mstr_symbols
J 0
(-4325 4575);
PAINT ORANGE (-4325 4575);
DISPLAY INVISIBLE (-4325 4575);
FORCEPROP 1 LAST SIZE 1B
J 0
(-4250 4525);
DISPLAY 1.404255 (-4250 4525);
PAINT GREEN (-4250 4525);
DISPLAY INVISIBLE (-4250 4525);
FORCEPROP 1 LAST BODY_TYPE PLUMBING
J 0
(-4370 4532);
DISPLAY 0.340426 (-4370 4532);
PAINT GREEN (-4370 4532);
DISPLAY INVISIBLE (-4370 4532);
FORCEPROP 1 LAST PATH I35
J 0
(-4250 4575);
DISPLAY 0.872340 (-4250 4575);
PAINT AQUA (-4250 4575);
DISPLAY INVISIBLE (-4250 4575);
FORCEPROP 2 LAST ROOM SB_DECOUPLING
J 0
(-4800 4650);
PAINT WHITE (-4800 4650);
DISPLAY INVISIBLE (-4800 4650);
FORCEPROP 1 LAST HDL_POWER GND
J 0
(-4325 4725);
DISPLAY 1.404255 (-4325 4725);
PAINT GREEN (-4325 4725);
DISPLAY INVISIBLE (-4325 4725);
FORCEADD CAP_A..1
(-4200 3925);
FORCEPROP 1 LAST LOCATION C2M16
J 0
(-4150 4025);
DISPLAY 0.617021 (-4150 4025);
PAINT AQUA (-4150 4025);
FORCEPROP 1 LAST PART_NUMBER D97712-004
J 0
(-4150 3775);
DISPLAY 0.617021 (-4150 3775);
PAINT BLUE (-4150 3775);
FORCEPROP 1 LAST VALUE 1.0UF
J 0
(-4150 3975);
DISPLAY 0.617021 (-4150 3975);
PAINT SKYBLUE (-4150 3975);
FORCEPROP 1 LAST TOLERANCE 10%
J 0
(-4150 3875);
DISPLAY 0.617021 (-4150 3875);
PAINT SKYBLUE (-4150 3875);
FORCEPROP 1 LAST PACK_TYPE 0402V
J 0
(-4150 3725);
DISPLAY 0.617021 (-4150 3725);
PAINT SKYBLUE (-4150 3725);
FORCEPROP 1 LAST VOLTAGE 6.3V
J 0
(-4150 3925);
DISPLAY 0.617021 (-4150 3925);
PAINT SKYBLUE (-4150 3925);
FORCEPROP 1 LAST MATERIAL X6S
J 0
(-4150 3825);
DISPLAY 0.617021 (-4150 3825);
PAINT SKYBLUE (-4150 3825);
FORCEPROP 1 LASTPIN (-4200 4025) $PN 1
J 0
(-4190 4005);
DISPLAY 0.617021 (-4190 4005);
PAINT WHITE (-4190 4005);
FORCEPROP 1 LASTPIN (-4200 3825) $PN 2
J 0
(-4190 3805);
DISPLAY 0.617021 (-4190 3805);
PAINT WHITE (-4190 3805);
FORCEPROP 2 LAST CDS_LOCATION C2M16
J 0
(-4150 4025);
DISPLAY 0.617021 (-4150 4025);
PAINT AQUA (-4150 4025);
DISPLAY INVISIBLE (-4150 4025);
FORCEPROP 2 LAST BOM_COST SB
J 0
(-4150 3675);
PAINT MONO (-4150 3675);
DISPLAY INVISIBLE (-4150 3675);
FORCEPROP 2 LAST CDS_LIB dev_discrete
J 0
(-4200 3925);
PAINT ORANGE (-4200 3925);
DISPLAY INVISIBLE (-4200 3925);
FORCEPROP 2 LAST CDS_SEC 1
J 0
(-4150 4125);
DISPLAY 1.361702 (-4150 4125);
PAINT ORANGE (-4150 4125);
DISPLAY INVISIBLE (-4150 4125);
FORCEPROP 2 LAST $SEC 1
J 0
(-4150 4125);
DISPLAY 0.914894 (-4150 4125);
PAINT MONO (-4150 4125);
DISPLAY INVISIBLE (-4150 4125);
FORCEPROP 1 LAST PATH I37
J 0
(-4150 4075);
DISPLAY 0.978723 (-4150 4075);
PAINT WHITE (-4150 4075);
DISPLAY INVISIBLE (-4150 4075);
FORCEPROP 2 LAST ROOM SB_DECOUPLING
J 0
(-4200 3925);
PAINT WHITE (-4200 3925);
DISPLAY INVISIBLE (-4200 3925);
FORCEADD CAP_A..1
(-3525 2750);
FORCEPROP 1 LAST LOCATION C7D3
J 0
(-3475 2850);
DISPLAY 0.617021 (-3475 2850);
PAINT AQUA (-3475 2850);
FORCEPROP 1 LAST PART_NUMBER E15431-004
J 0
(-3475 2600);
DISPLAY 0.617021 (-3475 2600);
PAINT BLUE (-3475 2600);
FORCEPROP 1 LAST VALUE 22.0UF
J 0
(-3475 2800);
DISPLAY 0.617021 (-3475 2800);
PAINT SKYBLUE (-3475 2800);
FORCEPROP 1 LAST TOLERANCE 20%
J 0
(-3475 2700);
DISPLAY 0.617021 (-3475 2700);
PAINT SKYBLUE (-3475 2700);
FORCEPROP 1 LAST PACK_TYPE 0603V
J 0
(-3475 2550);
DISPLAY 0.617021 (-3475 2550);
PAINT SKYBLUE (-3475 2550);
FORCEPROP 1 LAST VOLTAGE 4V
J 0
(-3475 2750);
DISPLAY 0.617021 (-3475 2750);
PAINT SKYBLUE (-3475 2750);
FORCEPROP 1 LAST MATERIAL X6S
J 0
(-3475 2650);
DISPLAY 0.617021 (-3475 2650);
PAINT SKYBLUE (-3475 2650);
FORCEPROP 2 LAST CDS_LOCATION C7D3
J 0
(-3475 2850);
DISPLAY 0.617021 (-3475 2850);
PAINT AQUA (-3475 2850);
DISPLAY INVISIBLE (-3475 2850);
FORCEPROP 2 LAST BOM_COST SB
J 0
(-3475 2500);
PAINT MONO (-3475 2500);
DISPLAY INVISIBLE (-3475 2500);
FORCEPROP 2 LAST CDS_LIB dev_discrete
J 0
(-3525 2750);
PAINT ORANGE (-3525 2750);
DISPLAY INVISIBLE (-3525 2750);
FORCEPROP 2 LAST CDS_SEC 1
J 0
(-3475 2950);
DISPLAY 1.361702 (-3475 2950);
PAINT ORANGE (-3475 2950);
DISPLAY INVISIBLE (-3475 2950);
FORCEPROP 2 LAST $SEC 1
J 0
(-3475 2950);
DISPLAY 0.914894 (-3475 2950);
PAINT MONO (-3475 2950);
DISPLAY INVISIBLE (-3475 2950);
FORCEPROP 1 LAST PATH I38
J 0
(-3475 2900);
DISPLAY 0.978723 (-3475 2900);
PAINT WHITE (-3475 2900);
DISPLAY INVISIBLE (-3475 2900);
FORCEPROP 2 LAST ROOM SB_DECOUPLING
J 0
(-3525 2750);
PAINT WHITE (-3525 2750);
DISPLAY INVISIBLE (-3525 2750);
FORCEPROP 1 LASTPIN (-3525 2850) $PN 1
J 0
(-3515 2830);
DISPLAY 1.063830 (-3515 2830);
PAINT WHITE (-3515 2830);
DISPLAY INVISIBLE (-3515 2830);
FORCEPROP 1 LASTPIN (-3525 2650) $PN 2
J 0
(-3515 2630);
DISPLAY 1.063830 (-3515 2630);
PAINT WHITE (-3515 2630);
DISPLAY INVISIBLE (-3515 2630);
FORCEADD CAP_A..1
(-3925 2750);
FORCEPROP 1 LAST LOCATION C8B4
J 0
(-3875 2850);
DISPLAY 0.617021 (-3875 2850);
PAINT AQUA (-3875 2850);
FORCEPROP 1 LAST PART_NUMBER E15431-004
J 0
(-3875 2600);
DISPLAY 0.617021 (-3875 2600);
PAINT BLUE (-3875 2600);
FORCEPROP 1 LAST VALUE 22.0UF
J 0
(-3875 2800);
DISPLAY 0.617021 (-3875 2800);
PAINT SKYBLUE (-3875 2800);
FORCEPROP 1 LAST TOLERANCE 20%
J 0
(-3875 2700);
DISPLAY 0.617021 (-3875 2700);
PAINT SKYBLUE (-3875 2700);
FORCEPROP 1 LAST PACK_TYPE 0603V
J 0
(-3875 2550);
DISPLAY 0.617021 (-3875 2550);
PAINT SKYBLUE (-3875 2550);
FORCEPROP 1 LAST VOLTAGE 4V
J 0
(-3875 2750);
DISPLAY 0.617021 (-3875 2750);
PAINT SKYBLUE (-3875 2750);
FORCEPROP 1 LAST MATERIAL X6S
J 0
(-3875 2650);
DISPLAY 0.617021 (-3875 2650);
PAINT SKYBLUE (-3875 2650);
FORCEPROP 2 LAST CDS_LOCATION C8B4
J 0
(-3875 2850);
DISPLAY 0.617021 (-3875 2850);
PAINT AQUA (-3875 2850);
DISPLAY INVISIBLE (-3875 2850);
FORCEPROP 2 LAST BOM_COST SB
J 0
(-3875 2500);
PAINT MONO (-3875 2500);
DISPLAY INVISIBLE (-3875 2500);
FORCEPROP 2 LAST CDS_LIB dev_discrete
J 0
(-3925 2750);
PAINT ORANGE (-3925 2750);
DISPLAY INVISIBLE (-3925 2750);
FORCEPROP 2 LAST CDS_SEC 1
J 0
(-3875 2950);
DISPLAY 1.361702 (-3875 2950);
PAINT ORANGE (-3875 2950);
DISPLAY INVISIBLE (-3875 2950);
FORCEPROP 2 LAST $SEC 1
J 0
(-3875 2950);
DISPLAY 0.914894 (-3875 2950);
PAINT MONO (-3875 2950);
DISPLAY INVISIBLE (-3875 2950);
FORCEPROP 1 LAST PATH I39
J 0
(-3875 2900);
DISPLAY 0.978723 (-3875 2900);
PAINT WHITE (-3875 2900);
DISPLAY INVISIBLE (-3875 2900);
FORCEPROP 2 LAST ROOM SB_DECOUPLING
J 0
(-3925 2750);
PAINT WHITE (-3925 2750);
DISPLAY INVISIBLE (-3925 2750);
FORCEPROP 1 LASTPIN (-3925 2850) $PN 1
J 0
(-3915 2830);
DISPLAY 1.063830 (-3915 2830);
PAINT WHITE (-3915 2830);
DISPLAY INVISIBLE (-3915 2830);
FORCEPROP 1 LASTPIN (-3925 2650) $PN 2
J 0
(-3915 2630);
DISPLAY 1.063830 (-3915 2630);
PAINT WHITE (-3915 2630);
DISPLAY INVISIBLE (-3915 2630);
FORCEADD CAP_A..1
(1725 2650);
FORCEPROP 1 LAST LOCATION C2N26
J 0
(1775 2750);
DISPLAY 0.617021 (1775 2750);
PAINT AQUA (1775 2750);
FORCEPROP 1 LAST PART_NUMBER D97712-004
J 0
(1775 2500);
DISPLAY 0.617021 (1775 2500);
PAINT BLUE (1775 2500);
FORCEPROP 1 LAST VALUE 1.0UF
J 0
(1775 2700);
DISPLAY 0.617021 (1775 2700);
PAINT SKYBLUE (1775 2700);
FORCEPROP 1 LAST TOLERANCE 10%
J 0
(1775 2600);
DISPLAY 0.617021 (1775 2600);
PAINT SKYBLUE (1775 2600);
FORCEPROP 1 LAST PACK_TYPE 0402V
J 0
(1775 2450);
DISPLAY 0.617021 (1775 2450);
PAINT SKYBLUE (1775 2450);
FORCEPROP 1 LAST VOLTAGE 6.3V
J 0
(1775 2650);
DISPLAY 0.617021 (1775 2650);
PAINT SKYBLUE (1775 2650);
FORCEPROP 1 LAST MATERIAL X6S
J 0
(1775 2550);
DISPLAY 0.617021 (1775 2550);
PAINT SKYBLUE (1775 2550);
FORCEPROP 1 LASTPIN (1725 2750) $PN 1
J 0
(1735 2730);
DISPLAY 0.617021 (1735 2730);
PAINT ORANGE (1735 2730);
FORCEPROP 1 LASTPIN (1725 2550) $PN 2
J 0
(1735 2530);
DISPLAY 0.617021 (1735 2530);
PAINT ORANGE (1735 2530);
FORCEPROP 2 LAST CDS_LOCATION C2N26
J 0
(1775 2750);
DISPLAY 0.617021 (1775 2750);
PAINT AQUA (1775 2750);
DISPLAY INVISIBLE (1775 2750);
FORCEPROP 2 LAST BOM_COST SB
J 0
(1775 2400);
PAINT MONO (1775 2400);
DISPLAY INVISIBLE (1775 2400);
FORCEPROP 2 LAST CDS_LIB dev_discrete
J 0
(1725 2650);
PAINT ORANGE (1725 2650);
DISPLAY INVISIBLE (1725 2650);
FORCEPROP 2 LAST CDS_SEC 1
J 0
(1775 2850);
DISPLAY 1.361702 (1775 2850);
PAINT ORANGE (1775 2850);
DISPLAY INVISIBLE (1775 2850);
FORCEPROP 2 LAST $SEC 1
J 0
(1775 2850);
DISPLAY 0.914894 (1775 2850);
PAINT MONO (1775 2850);
DISPLAY INVISIBLE (1775 2850);
FORCEPROP 1 LAST PATH I4
J 0
(1775 2800);
DISPLAY 0.978723 (1775 2800);
PAINT WHITE (1775 2800);
DISPLAY INVISIBLE (1775 2800);
FORCEPROP 2 LAST ROOM SB_DECOUPLING
J 0
(1725 2650);
PAINT WHITE (1725 2650);
DISPLAY INVISIBLE (1725 2650);
FORCEADD GND..1
(-4375 3575);
FORCEPROP 3 LASTPIN (-4375 3625) SIG_NAME GND\g
J 0
(-4365 3635);
DISPLAY 0.659574 (-4365 3635);
PAINT MONO (-4365 3635);
DISPLAY INVISIBLE (-4365 3635);
FORCEPROP 1 LAST VOLTAGE 0
J 0
(-4375 3575);
PAINT SKYBLUE (-4375 3575);
DISPLAY INVISIBLE (-4375 3575);
FORCEPROP 2 LAST BOM_COST SB
J 0
(-4425 3650);
PAINT MONO (-4425 3650);
DISPLAY INVISIBLE (-4425 3650);
FORCEPROP 1 LAST SIZE 1B
J 0
(-4300 3525);
DISPLAY 1.404255 (-4300 3525);
PAINT GREEN (-4300 3525);
DISPLAY INVISIBLE (-4300 3525);
FORCEPROP 2 LAST CDS_LIB mstr_symbols
J 0
(-4375 3575);
PAINT ORANGE (-4375 3575);
DISPLAY INVISIBLE (-4375 3575);
FORCEPROP 1 LAST BODY_TYPE PLUMBING
J 0
(-4420 3532);
DISPLAY 0.340426 (-4420 3532);
PAINT GREEN (-4420 3532);
DISPLAY INVISIBLE (-4420 3532);
FORCEPROP 1 LAST PATH I40
J 0
(-4300 3575);
DISPLAY 0.872340 (-4300 3575);
PAINT AQUA (-4300 3575);
DISPLAY INVISIBLE (-4300 3575);
FORCEPROP 2 LAST ROOM SB_DECOUPLING
J 0
(-4850 3650);
PAINT WHITE (-4850 3650);
DISPLAY INVISIBLE (-4850 3650);
FORCEPROP 1 LAST HDL_POWER GND
J 0
(-4375 3725);
DISPLAY 1.404255 (-4375 3725);
PAINT GREEN (-4375 3725);
DISPLAY INVISIBLE (-4375 3725);
FORCEADD CAP_A..1
(-4350 2750);
FORCEPROP 1 LAST LOCATION C8B1
J 0
(-4300 2850);
DISPLAY 0.617021 (-4300 2850);
PAINT AQUA (-4300 2850);
FORCEPROP 1 LAST PART_NUMBER E15431-004
J 0
(-4300 2600);
DISPLAY 0.617021 (-4300 2600);
PAINT BLUE (-4300 2600);
FORCEPROP 1 LAST VALUE 22.0UF
J 0
(-4300 2800);
DISPLAY 0.617021 (-4300 2800);
PAINT SKYBLUE (-4300 2800);
FORCEPROP 1 LAST TOLERANCE 20%
J 0
(-4300 2700);
DISPLAY 0.617021 (-4300 2700);
PAINT SKYBLUE (-4300 2700);
FORCEPROP 1 LAST PACK_TYPE 0603V
J 0
(-4300 2550);
DISPLAY 0.617021 (-4300 2550);
PAINT SKYBLUE (-4300 2550);
FORCEPROP 1 LAST VOLTAGE 4V
J 0
(-4300 2750);
DISPLAY 0.617021 (-4300 2750);
PAINT SKYBLUE (-4300 2750);
FORCEPROP 1 LAST MATERIAL X6S
J 0
(-4300 2650);
DISPLAY 0.617021 (-4300 2650);
PAINT SKYBLUE (-4300 2650);
FORCEPROP 2 LAST CDS_LOCATION C8B1
J 0
(-4300 2850);
DISPLAY 0.617021 (-4300 2850);
PAINT AQUA (-4300 2850);
DISPLAY INVISIBLE (-4300 2850);
FORCEPROP 2 LAST BOM_COST SB
J 0
(-4300 2500);
PAINT MONO (-4300 2500);
DISPLAY INVISIBLE (-4300 2500);
FORCEPROP 2 LAST CDS_LIB dev_discrete
J 0
(-4350 2750);
PAINT ORANGE (-4350 2750);
DISPLAY INVISIBLE (-4350 2750);
FORCEPROP 2 LAST CDS_SEC 1
J 0
(-4300 2950);
DISPLAY 1.361702 (-4300 2950);
PAINT ORANGE (-4300 2950);
DISPLAY INVISIBLE (-4300 2950);
FORCEPROP 2 LAST $SEC 1
J 0
(-4300 2950);
DISPLAY 0.914894 (-4300 2950);
PAINT MONO (-4300 2950);
DISPLAY INVISIBLE (-4300 2950);
FORCEPROP 1 LAST PATH I41
J 0
(-4300 2900);
DISPLAY 0.978723 (-4300 2900);
PAINT WHITE (-4300 2900);
DISPLAY INVISIBLE (-4300 2900);
FORCEPROP 2 LAST ROOM SB_DECOUPLING
J 0
(-4350 2750);
PAINT WHITE (-4350 2750);
DISPLAY INVISIBLE (-4350 2750);
FORCEPROP 1 LASTPIN (-4350 2850) $PN 1
J 0
(-4340 2830);
DISPLAY 1.063830 (-4340 2830);
PAINT WHITE (-4340 2830);
DISPLAY INVISIBLE (-4340 2830);
FORCEPROP 1 LASTPIN (-4350 2650) $PN 2
J 0
(-4340 2630);
DISPLAY 1.063830 (-4340 2630);
PAINT WHITE (-4340 2630);
DISPLAY INVISIBLE (-4340 2630);
FORCEADD CAP_A..1
(-4600 3925);
FORCEPROP 1 LAST PART_NUMBER D97712-004
J 0
(-4550 3775);
DISPLAY 0.617021 (-4550 3775);
PAINT BLUE (-4550 3775);
FORCEPROP 1 LAST VALUE 1.0UF
J 0
(-4550 3975);
DISPLAY 0.617021 (-4550 3975);
PAINT SKYBLUE (-4550 3975);
FORCEPROP 1 LAST TOLERANCE 10%
J 0
(-4550 3875);
DISPLAY 0.617021 (-4550 3875);
PAINT SKYBLUE (-4550 3875);
FORCEPROP 1 LAST PACK_TYPE 0402V
J 0
(-4550 3725);
DISPLAY 0.617021 (-4550 3725);
PAINT SKYBLUE (-4550 3725);
FORCEPROP 1 LAST VOLTAGE 6.3V
J 0
(-4550 3925);
DISPLAY 0.617021 (-4550 3925);
PAINT SKYBLUE (-4550 3925);
FORCEPROP 1 LAST MATERIAL X6S
J 0
(-4550 3825);
DISPLAY 0.617021 (-4550 3825);
PAINT SKYBLUE (-4550 3825);
FORCEPROP 1 LASTPIN (-4600 4025) $PN 1
J 0
(-4590 4005);
DISPLAY 0.617021 (-4590 4005);
PAINT WHITE (-4590 4005);
FORCEPROP 1 LASTPIN (-4600 3825) $PN 2
J 0
(-4590 3805);
DISPLAY 0.617021 (-4590 3805);
PAINT WHITE (-4590 3805);
FORCEPROP 1 LAST LOCATION C3N23
J 0
(-4550 4025);
DISPLAY 0.617021 (-4550 4025);
PAINT AQUA (-4550 4025);
FORCEPROP 2 LAST CDS_LOCATION C3N23
J 0
(-4550 4025);
DISPLAY 0.617021 (-4550 4025);
PAINT AQUA (-4550 4025);
DISPLAY INVISIBLE (-4550 4025);
FORCEPROP 2 LAST BOM_COST SB
J 0
(-4550 3675);
PAINT MONO (-4550 3675);
DISPLAY INVISIBLE (-4550 3675);
FORCEPROP 2 LAST CDS_LIB dev_discrete
J 0
(-4600 3925);
PAINT ORANGE (-4600 3925);
DISPLAY INVISIBLE (-4600 3925);
FORCEPROP 2 LAST CDS_SEC 1
J 0
(-4550 4125);
PAINT MONO (-4550 4125);
DISPLAY INVISIBLE (-4550 4125);
FORCEPROP 2 LAST $SEC 1
J 0
(-4550 4125);
PAINT MONO (-4550 4125);
DISPLAY INVISIBLE (-4550 4125);
FORCEPROP 1 LAST PATH I42
J 0
(-4550 4075);
DISPLAY 0.978723 (-4550 4075);
PAINT WHITE (-4550 4075);
DISPLAY INVISIBLE (-4550 4075);
FORCEPROP 2 LAST ROOM SB_DECOUPLING
J 0
(-4600 3925);
PAINT WHITE (-4600 3925);
DISPLAY INVISIBLE (-4600 3925);
FORCEADD CAP_A..1
(-4725 2750);
FORCEPROP 1 LAST LOCATION C2M1
J 0
(-4675 2850);
DISPLAY 0.617021 (-4675 2850);
PAINT AQUA (-4675 2850);
FORCEPROP 1 LAST PART_NUMBER E15431-004
J 0
(-4675 2600);
DISPLAY 0.617021 (-4675 2600);
PAINT BLUE (-4675 2600);
FORCEPROP 1 LAST VALUE 22.0UF
J 0
(-4675 2800);
DISPLAY 0.617021 (-4675 2800);
PAINT SKYBLUE (-4675 2800);
FORCEPROP 1 LAST TOLERANCE 20%
J 0
(-4675 2700);
DISPLAY 0.617021 (-4675 2700);
PAINT SKYBLUE (-4675 2700);
FORCEPROP 1 LAST PACK_TYPE 0603V
J 0
(-4675 2550);
DISPLAY 0.617021 (-4675 2550);
PAINT SKYBLUE (-4675 2550);
FORCEPROP 1 LAST VOLTAGE 4V
J 0
(-4675 2750);
DISPLAY 0.617021 (-4675 2750);
PAINT SKYBLUE (-4675 2750);
FORCEPROP 1 LAST MATERIAL X6S
J 0
(-4675 2650);
DISPLAY 0.617021 (-4675 2650);
PAINT SKYBLUE (-4675 2650);
FORCEPROP 2 LAST CDS_LOCATION C2M1
J 0
(-4675 2850);
DISPLAY 0.617021 (-4675 2850);
PAINT AQUA (-4675 2850);
DISPLAY INVISIBLE (-4675 2850);
FORCEPROP 2 LAST BOM_COST SB
J 0
(-4675 2500);
PAINT MONO (-4675 2500);
DISPLAY INVISIBLE (-4675 2500);
FORCEPROP 2 LAST CDS_LIB dev_discrete
J 0
(-4725 2750);
PAINT ORANGE (-4725 2750);
DISPLAY INVISIBLE (-4725 2750);
FORCEPROP 2 LAST CDS_SEC 1
J 0
(-4675 2950);
DISPLAY 1.361702 (-4675 2950);
PAINT ORANGE (-4675 2950);
DISPLAY INVISIBLE (-4675 2950);
FORCEPROP 2 LAST $SEC 1
J 0
(-4675 2950);
DISPLAY 0.914894 (-4675 2950);
PAINT MONO (-4675 2950);
DISPLAY INVISIBLE (-4675 2950);
FORCEPROP 1 LAST PATH I43
J 0
(-4675 2900);
DISPLAY 0.978723 (-4675 2900);
PAINT WHITE (-4675 2900);
DISPLAY INVISIBLE (-4675 2900);
FORCEPROP 2 LAST ROOM SB_DECOUPLING
J 0
(-4725 2750);
PAINT WHITE (-4725 2750);
DISPLAY INVISIBLE (-4725 2750);
FORCEPROP 1 LASTPIN (-4725 2850) $PN 1
J 0
(-4715 2830);
DISPLAY 1.063830 (-4715 2830);
PAINT WHITE (-4715 2830);
DISPLAY INVISIBLE (-4715 2830);
FORCEPROP 1 LASTPIN (-4725 2650) $PN 2
J 0
(-4715 2630);
DISPLAY 1.063830 (-4715 2630);
PAINT WHITE (-4715 2630);
DISPLAY INVISIBLE (-4715 2630);
FORCEADD P1V8_PCH_STBY..1
(-4850 3025);
FORCEPROP 3 LASTPIN (-4850 2975) SIG_NAME P1V8_PCH_STBY\g
J 0
(-4840 2985);
DISPLAY 0.659574 (-4840 2985);
PAINT MONO (-4840 2985);
DISPLAY INVISIBLE (-4840 2985);
FORCEPROP 1 LAST VOLTAGE 1.8V
J 0
(-4895 2982);
DISPLAY 0.340426 (-4895 2982);
PAINT SKYBLUE (-4895 2982);
DISPLAY INVISIBLE (-4895 2982);
FORCEPROP 2 LAST BOM_COST SB
J 0
(-4850 3175);
PAINT MONO (-4850 3175);
DISPLAY INVISIBLE (-4850 3175);
FORCEPROP 2 LAST CDS_LIB mstr_symbols
J 0
(-4850 3025);
PAINT ORANGE (-4850 3025);
DISPLAY INVISIBLE (-4850 3025);
FORCEPROP 1 LAST BODY_TYPE PLUMBING
J 0
(-4895 2982);
DISPLAY 0.340426 (-4895 2982);
PAINT GREEN (-4895 2982);
DISPLAY INVISIBLE (-4895 2982);
FORCEPROP 1 LAST PATH I44
J 0
(-4800 3050);
DISPLAY 0.872340 (-4800 3050);
PAINT AQUA (-4800 3050);
DISPLAY INVISIBLE (-4800 3050);
FORCEPROP 2 LAST ROOM SB_DECOUPLING
J 0
(-4850 3125);
DISPLAY 1.361702 (-4850 3125);
PAINT WHITE (-4850 3125);
DISPLAY INVISIBLE (-4850 3125);
FORCEPROP 1 LAST HDL_POWER P1V8_PCH_STBY
J 1
(-4850 3075);
DISPLAY 0.872340 (-4850 3075);
PAINT GREEN (-4850 3075);
DISPLAY INVISIBLE (-4850 3075);
FORCEADD CAP_A..1
(-5150 2750);
FORCEPROP 1 LAST LOCATION C2M2
J 0
(-5100 2850);
DISPLAY 0.617021 (-5100 2850);
PAINT AQUA (-5100 2850);
FORCEPROP 1 LAST PART_NUMBER E15431-004
J 0
(-5100 2600);
DISPLAY 0.617021 (-5100 2600);
PAINT BLUE (-5100 2600);
FORCEPROP 1 LAST VALUE 22.0UF
J 0
(-5100 2800);
DISPLAY 0.617021 (-5100 2800);
PAINT SKYBLUE (-5100 2800);
FORCEPROP 1 LAST TOLERANCE 20%
J 0
(-5100 2700);
DISPLAY 0.617021 (-5100 2700);
PAINT SKYBLUE (-5100 2700);
FORCEPROP 1 LAST PACK_TYPE 0603V
J 0
(-5100 2550);
DISPLAY 0.617021 (-5100 2550);
PAINT SKYBLUE (-5100 2550);
FORCEPROP 1 LAST VOLTAGE 4V
J 0
(-5100 2750);
DISPLAY 0.617021 (-5100 2750);
PAINT SKYBLUE (-5100 2750);
FORCEPROP 1 LAST MATERIAL X6S
J 0
(-5100 2650);
DISPLAY 0.617021 (-5100 2650);
PAINT SKYBLUE (-5100 2650);
FORCEPROP 2 LAST CDS_LOCATION C2M2
J 0
(-5100 2850);
DISPLAY 0.617021 (-5100 2850);
PAINT AQUA (-5100 2850);
DISPLAY INVISIBLE (-5100 2850);
FORCEPROP 2 LAST BOM_COST SB
J 0
(-5100 2500);
PAINT MONO (-5100 2500);
DISPLAY INVISIBLE (-5100 2500);
FORCEPROP 2 LAST CDS_LIB dev_discrete
J 0
(-5150 2750);
PAINT ORANGE (-5150 2750);
DISPLAY INVISIBLE (-5150 2750);
FORCEPROP 2 LAST CDS_SEC 1
J 0
(-5100 2950);
DISPLAY 1.361702 (-5100 2950);
PAINT ORANGE (-5100 2950);
DISPLAY INVISIBLE (-5100 2950);
FORCEPROP 2 LAST $SEC 1
J 0
(-5100 2950);
DISPLAY 0.914894 (-5100 2950);
PAINT MONO (-5100 2950);
DISPLAY INVISIBLE (-5100 2950);
FORCEPROP 1 LAST PATH I45
J 0
(-5100 2900);
DISPLAY 0.978723 (-5100 2900);
PAINT WHITE (-5100 2900);
DISPLAY INVISIBLE (-5100 2900);
FORCEPROP 2 LAST ROOM SB_DECOUPLING
J 0
(-5150 2750);
PAINT WHITE (-5150 2750);
DISPLAY INVISIBLE (-5150 2750);
FORCEPROP 1 LASTPIN (-5150 2850) $PN 1
J 0
(-5140 2830);
DISPLAY 1.063830 (-5140 2830);
PAINT WHITE (-5140 2830);
DISPLAY INVISIBLE (-5140 2830);
FORCEPROP 1 LASTPIN (-5150 2650) $PN 2
J 0
(-5140 2630);
DISPLAY 1.063830 (-5140 2630);
PAINT WHITE (-5140 2630);
DISPLAY INVISIBLE (-5140 2630);
FORCEADD GND..1
(-4075 2425);
FORCEPROP 3 LASTPIN (-4075 2475) SIG_NAME GND\g
J 0
(-4065 2485);
DISPLAY 0.659574 (-4065 2485);
PAINT MONO (-4065 2485);
DISPLAY INVISIBLE (-4065 2485);
FORCEPROP 1 LAST VOLTAGE 0
J 0
(-4075 2425);
PAINT SKYBLUE (-4075 2425);
DISPLAY INVISIBLE (-4075 2425);
FORCEPROP 1 LAST SIZE 1B
J 0
(-4000 2375);
DISPLAY 1.404255 (-4000 2375);
PAINT GREEN (-4000 2375);
DISPLAY INVISIBLE (-4000 2375);
FORCEPROP 2 LAST CDS_LIB mstr_symbols
J 0
(-4075 2425);
PAINT ORANGE (-4075 2425);
DISPLAY INVISIBLE (-4075 2425);
FORCEPROP 2 LAST BOM_COST SB
J 0
(-4125 2500);
PAINT MONO (-4125 2500);
DISPLAY INVISIBLE (-4125 2500);
FORCEPROP 1 LAST BODY_TYPE PLUMBING
J 0
(-4120 2382);
DISPLAY 0.340426 (-4120 2382);
PAINT GREEN (-4120 2382);
DISPLAY INVISIBLE (-4120 2382);
FORCEPROP 1 LAST PATH I46
J 0
(-4000 2425);
DISPLAY 0.872340 (-4000 2425);
PAINT AQUA (-4000 2425);
DISPLAY INVISIBLE (-4000 2425);
FORCEPROP 2 LAST ROOM SB_DECOUPLING
J 0
(-4550 2500);
PAINT WHITE (-4550 2500);
DISPLAY INVISIBLE (-4550 2500);
FORCEPROP 1 LAST HDL_POWER GND
J 0
(-4075 2575);
DISPLAY 1.404255 (-4075 2575);
PAINT GREEN (-4075 2575);
DISPLAY INVISIBLE (-4075 2575);
FORCEADD CAP_A..1
(-3600 1475);
FORCEPROP 1 LAST LOCATION C2N15
J 0
(-3550 1575);
DISPLAY 0.617021 (-3550 1575);
PAINT AQUA (-3550 1575);
FORCEPROP 1 LAST PART_NUMBER D97712-004
J 0
(-3550 1325);
DISPLAY 0.617021 (-3550 1325);
PAINT BLUE (-3550 1325);
FORCEPROP 1 LAST VALUE 1.0UF
J 0
(-3550 1525);
DISPLAY 0.617021 (-3550 1525);
PAINT SKYBLUE (-3550 1525);
FORCEPROP 1 LAST TOLERANCE 10%
J 0
(-3550 1425);
DISPLAY 0.617021 (-3550 1425);
PAINT SKYBLUE (-3550 1425);
FORCEPROP 1 LAST PACK_TYPE 0402V
J 0
(-3550 1275);
DISPLAY 0.617021 (-3550 1275);
PAINT SKYBLUE (-3550 1275);
FORCEPROP 1 LAST VOLTAGE 6.3V
J 0
(-3550 1475);
DISPLAY 0.617021 (-3550 1475);
PAINT SKYBLUE (-3550 1475);
FORCEPROP 1 LAST MATERIAL X6S
J 0
(-3550 1375);
DISPLAY 0.617021 (-3550 1375);
PAINT SKYBLUE (-3550 1375);
FORCEPROP 1 LASTPIN (-3600 1575) $PN 1
J 0
(-3590 1555);
DISPLAY 0.617021 (-3590 1555);
PAINT WHITE (-3590 1555);
FORCEPROP 1 LASTPIN (-3600 1375) $PN 2
J 0
(-3590 1355);
DISPLAY 0.617021 (-3590 1355);
PAINT WHITE (-3590 1355);
FORCEPROP 2 LAST CDS_LOCATION C2N15
J 0
(-3550 1575);
DISPLAY 0.617021 (-3550 1575);
PAINT AQUA (-3550 1575);
DISPLAY INVISIBLE (-3550 1575);
FORCEPROP 2 LAST BOM_COST SB
J 0
(-3550 1225);
PAINT MONO (-3550 1225);
DISPLAY INVISIBLE (-3550 1225);
FORCEPROP 2 LAST CDS_LIB dev_discrete
J 0
(-3600 1475);
PAINT ORANGE (-3600 1475);
DISPLAY INVISIBLE (-3600 1475);
FORCEPROP 2 LAST CDS_SEC 1
J 0
(-3550 1675);
DISPLAY 1.361702 (-3550 1675);
PAINT ORANGE (-3550 1675);
DISPLAY INVISIBLE (-3550 1675);
FORCEPROP 2 LAST $SEC 1
J 0
(-3550 1675);
DISPLAY 0.914894 (-3550 1675);
PAINT MONO (-3550 1675);
DISPLAY INVISIBLE (-3550 1675);
FORCEPROP 1 LAST PATH I47
J 0
(-3550 1625);
DISPLAY 0.978723 (-3550 1625);
PAINT WHITE (-3550 1625);
DISPLAY INVISIBLE (-3550 1625);
FORCEPROP 2 LAST ROOM SB_DECOUPLING
J 0
(-3600 1475);
PAINT WHITE (-3600 1475);
DISPLAY INVISIBLE (-3600 1475);
FORCEADD GND..1
(-3750 1150);
FORCEPROP 3 LASTPIN (-3750 1200) SIG_NAME GND\g
J 0
(-3740 1210);
DISPLAY 0.659574 (-3740 1210);
PAINT MONO (-3740 1210);
DISPLAY INVISIBLE (-3740 1210);
FORCEPROP 1 LAST VOLTAGE 0
J 0
(-3750 1150);
PAINT SKYBLUE (-3750 1150);
DISPLAY INVISIBLE (-3750 1150);
FORCEPROP 2 LAST BOM_COST SB
J 0
(-3800 1225);
PAINT MONO (-3800 1225);
DISPLAY INVISIBLE (-3800 1225);
FORCEPROP 2 LAST CDS_LIB mstr_symbols
J 0
(-3750 1150);
PAINT ORANGE (-3750 1150);
DISPLAY INVISIBLE (-3750 1150);
FORCEPROP 1 LAST SIZE 1B
J 0
(-3675 1100);
DISPLAY 1.404255 (-3675 1100);
PAINT GREEN (-3675 1100);
DISPLAY INVISIBLE (-3675 1100);
FORCEPROP 1 LAST BODY_TYPE PLUMBING
J 0
(-3795 1107);
DISPLAY 0.340426 (-3795 1107);
PAINT GREEN (-3795 1107);
DISPLAY INVISIBLE (-3795 1107);
FORCEPROP 1 LAST PATH I48
J 0
(-3675 1150);
DISPLAY 0.872340 (-3675 1150);
PAINT AQUA (-3675 1150);
DISPLAY INVISIBLE (-3675 1150);
FORCEPROP 2 LAST ROOM SB_DECOUPLING
J 0
(-4225 1225);
PAINT WHITE (-4225 1225);
DISPLAY INVISIBLE (-4225 1225);
FORCEPROP 1 LAST HDL_POWER GND
J 0
(-3750 1300);
DISPLAY 1.404255 (-3750 1300);
PAINT GREEN (-3750 1300);
DISPLAY INVISIBLE (-3750 1300);
FORCEADD CAP_A..1
(-3975 1475);
FORCEPROP 1 LAST LOCATION C3N21
J 0
(-3925 1575);
DISPLAY 0.617021 (-3925 1575);
PAINT AQUA (-3925 1575);
FORCEPROP 1 LAST PART_NUMBER D97712-004
J 0
(-3925 1325);
DISPLAY 0.617021 (-3925 1325);
PAINT BLUE (-3925 1325);
FORCEPROP 1 LAST VALUE 1.0UF
J 0
(-3925 1525);
DISPLAY 0.617021 (-3925 1525);
PAINT SKYBLUE (-3925 1525);
FORCEPROP 1 LAST TOLERANCE 10%
J 0
(-3925 1425);
DISPLAY 0.617021 (-3925 1425);
PAINT SKYBLUE (-3925 1425);
FORCEPROP 1 LAST PACK_TYPE 0402V
J 0
(-3925 1275);
DISPLAY 0.617021 (-3925 1275);
PAINT SKYBLUE (-3925 1275);
FORCEPROP 1 LAST VOLTAGE 6.3V
J 0
(-3925 1475);
DISPLAY 0.617021 (-3925 1475);
PAINT SKYBLUE (-3925 1475);
FORCEPROP 1 LAST MATERIAL X6S
J 0
(-3925 1375);
DISPLAY 0.617021 (-3925 1375);
PAINT SKYBLUE (-3925 1375);
FORCEPROP 1 LASTPIN (-3975 1575) $PN 1
J 0
(-3965 1555);
DISPLAY 0.617021 (-3965 1555);
PAINT WHITE (-3965 1555);
FORCEPROP 1 LASTPIN (-3975 1375) $PN 2
J 0
(-3965 1355);
DISPLAY 0.617021 (-3965 1355);
PAINT WHITE (-3965 1355);
FORCEPROP 2 LAST CDS_LOCATION C3N21
J 0
(-3925 1575);
DISPLAY 0.617021 (-3925 1575);
PAINT AQUA (-3925 1575);
DISPLAY INVISIBLE (-3925 1575);
FORCEPROP 2 LAST BOM_COST SB
J 0
(-3925 1225);
PAINT MONO (-3925 1225);
DISPLAY INVISIBLE (-3925 1225);
FORCEPROP 2 LAST CDS_LIB dev_discrete
J 0
(-3975 1475);
PAINT ORANGE (-3975 1475);
DISPLAY INVISIBLE (-3975 1475);
FORCEPROP 2 LAST CDS_SEC 1
J 0
(-3925 1675);
DISPLAY 1.361702 (-3925 1675);
PAINT ORANGE (-3925 1675);
DISPLAY INVISIBLE (-3925 1675);
FORCEPROP 2 LAST $SEC 1
J 0
(-3925 1675);
DISPLAY 0.914894 (-3925 1675);
PAINT MONO (-3925 1675);
DISPLAY INVISIBLE (-3925 1675);
FORCEPROP 1 LAST PATH I49
J 0
(-3925 1625);
DISPLAY 0.978723 (-3925 1625);
PAINT WHITE (-3925 1625);
DISPLAY INVISIBLE (-3925 1625);
FORCEPROP 2 LAST ROOM SB_DECOUPLING
J 0
(-3975 1475);
PAINT WHITE (-3975 1475);
DISPLAY INVISIBLE (-3975 1475);
FORCEADD CAP_A..1
(-4350 1475);
FORCEPROP 1 LAST LOCATION C3N25
J 0
(-4300 1575);
DISPLAY 0.617021 (-4300 1575);
PAINT AQUA (-4300 1575);
FORCEPROP 1 LAST PART_NUMBER D97712-004
J 0
(-4300 1325);
DISPLAY 0.617021 (-4300 1325);
PAINT BLUE (-4300 1325);
FORCEPROP 1 LAST VALUE 1.0UF
J 0
(-4300 1525);
DISPLAY 0.617021 (-4300 1525);
PAINT SKYBLUE (-4300 1525);
FORCEPROP 1 LAST TOLERANCE 10%
J 0
(-4300 1425);
DISPLAY 0.617021 (-4300 1425);
PAINT SKYBLUE (-4300 1425);
FORCEPROP 1 LAST PACK_TYPE 0402V
J 0
(-4300 1275);
DISPLAY 0.617021 (-4300 1275);
PAINT SKYBLUE (-4300 1275);
FORCEPROP 1 LAST VOLTAGE 6.3V
J 0
(-4300 1475);
DISPLAY 0.617021 (-4300 1475);
PAINT SKYBLUE (-4300 1475);
FORCEPROP 1 LAST MATERIAL X6S
J 0
(-4300 1375);
DISPLAY 0.617021 (-4300 1375);
PAINT SKYBLUE (-4300 1375);
FORCEPROP 1 LASTPIN (-4350 1575) $PN 1
J 0
(-4340 1555);
DISPLAY 0.617021 (-4340 1555);
PAINT WHITE (-4340 1555);
FORCEPROP 1 LASTPIN (-4350 1375) $PN 2
J 0
(-4340 1355);
DISPLAY 0.617021 (-4340 1355);
PAINT WHITE (-4340 1355);
FORCEPROP 2 LAST CDS_LOCATION C3N25
J 0
(-4300 1575);
DISPLAY 0.617021 (-4300 1575);
PAINT AQUA (-4300 1575);
DISPLAY INVISIBLE (-4300 1575);
FORCEPROP 2 LAST BOM_COST SB
J 0
(-4300 1225);
PAINT MONO (-4300 1225);
DISPLAY INVISIBLE (-4300 1225);
FORCEPROP 2 LAST CDS_LIB dev_discrete
J 0
(-4350 1475);
PAINT ORANGE (-4350 1475);
DISPLAY INVISIBLE (-4350 1475);
FORCEPROP 2 LAST CDS_SEC 1
J 0
(-4300 1675);
PAINT MONO (-4300 1675);
DISPLAY INVISIBLE (-4300 1675);
FORCEPROP 2 LAST $SEC 1
J 0
(-4300 1675);
PAINT MONO (-4300 1675);
DISPLAY INVISIBLE (-4300 1675);
FORCEPROP 1 LAST PATH I50
J 0
(-4300 1625);
DISPLAY 0.978723 (-4300 1625);
PAINT WHITE (-4300 1625);
DISPLAY INVISIBLE (-4300 1625);
FORCEPROP 2 LAST ROOM SB_DECOUPLING
J 0
(-4350 1475);
PAINT WHITE (-4350 1475);
DISPLAY INVISIBLE (-4350 1475);
FORCEADD P1V8_PCH_STBY..1
(-4950 1750);
FORCEPROP 3 LASTPIN (-4950 1700) SIG_NAME P1V8_PCH_STBY\g
J 0
(-4940 1710);
DISPLAY 0.659574 (-4940 1710);
PAINT MONO (-4940 1710);
DISPLAY INVISIBLE (-4940 1710);
FORCEPROP 1 LAST VOLTAGE 1.8V
J 0
(-4995 1707);
DISPLAY 0.340426 (-4995 1707);
PAINT SKYBLUE (-4995 1707);
DISPLAY INVISIBLE (-4995 1707);
FORCEPROP 2 LAST BOM_COST SB
J 0
(-4950 1900);
PAINT MONO (-4950 1900);
DISPLAY INVISIBLE (-4950 1900);
FORCEPROP 2 LAST CDS_LIB mstr_symbols
J 0
(-4950 1750);
PAINT ORANGE (-4950 1750);
DISPLAY INVISIBLE (-4950 1750);
FORCEPROP 1 LAST BODY_TYPE PLUMBING
J 0
(-4995 1707);
DISPLAY 0.340426 (-4995 1707);
PAINT GREEN (-4995 1707);
DISPLAY INVISIBLE (-4995 1707);
FORCEPROP 1 LAST PATH I51
J 0
(-4900 1775);
DISPLAY 0.872340 (-4900 1775);
PAINT AQUA (-4900 1775);
DISPLAY INVISIBLE (-4900 1775);
FORCEPROP 2 LAST ROOM SB_DECOUPLING
J 0
(-4950 1850);
DISPLAY 1.361702 (-4950 1850);
PAINT WHITE (-4950 1850);
DISPLAY INVISIBLE (-4950 1850);
FORCEPROP 1 LAST HDL_POWER P1V8_PCH_STBY
J 1
(-4950 1800);
DISPLAY 0.872340 (-4950 1800);
PAINT GREEN (-4950 1800);
DISPLAY INVISIBLE (-4950 1800);
FORCEADD CAP_A..1
(-4775 1475);
FORCEPROP 1 LAST LOCATION C2N16
J 0
(-4725 1575);
DISPLAY 0.617021 (-4725 1575);
PAINT AQUA (-4725 1575);
FORCEPROP 1 LAST PART_NUMBER D97712-004
J 0
(-4725 1325);
DISPLAY 0.617021 (-4725 1325);
PAINT BLUE (-4725 1325);
FORCEPROP 1 LAST VALUE 1.0UF
J 0
(-4725 1525);
DISPLAY 0.617021 (-4725 1525);
PAINT SKYBLUE (-4725 1525);
FORCEPROP 1 LAST TOLERANCE 10%
J 0
(-4725 1425);
DISPLAY 0.617021 (-4725 1425);
PAINT SKYBLUE (-4725 1425);
FORCEPROP 1 LAST PACK_TYPE 0402V
J 0
(-4725 1275);
DISPLAY 0.617021 (-4725 1275);
PAINT SKYBLUE (-4725 1275);
FORCEPROP 1 LAST VOLTAGE 6.3V
J 0
(-4725 1475);
DISPLAY 0.617021 (-4725 1475);
PAINT SKYBLUE (-4725 1475);
FORCEPROP 1 LAST MATERIAL X6S
J 0
(-4725 1375);
DISPLAY 0.617021 (-4725 1375);
PAINT SKYBLUE (-4725 1375);
FORCEPROP 1 LASTPIN (-4775 1575) $PN 1
J 0
(-4765 1555);
DISPLAY 0.617021 (-4765 1555);
PAINT WHITE (-4765 1555);
FORCEPROP 1 LASTPIN (-4775 1375) $PN 2
J 0
(-4765 1355);
DISPLAY 0.617021 (-4765 1355);
PAINT WHITE (-4765 1355);
FORCEPROP 2 LAST CDS_LOCATION C2N16
J 0
(-4725 1575);
DISPLAY 0.617021 (-4725 1575);
PAINT AQUA (-4725 1575);
DISPLAY INVISIBLE (-4725 1575);
FORCEPROP 2 LAST BOM_COST SB
J 0
(-4725 1225);
PAINT MONO (-4725 1225);
DISPLAY INVISIBLE (-4725 1225);
FORCEPROP 2 LAST CDS_LIB dev_discrete
J 0
(-4775 1475);
PAINT ORANGE (-4775 1475);
DISPLAY INVISIBLE (-4775 1475);
FORCEPROP 2 LAST CDS_SEC 1
J 0
(-4725 1675);
PAINT MONO (-4725 1675);
DISPLAY INVISIBLE (-4725 1675);
FORCEPROP 2 LAST $SEC 1
J 0
(-4725 1675);
PAINT MONO (-4725 1675);
DISPLAY INVISIBLE (-4725 1675);
FORCEPROP 1 LAST PATH I52
J 0
(-4725 1625);
DISPLAY 0.978723 (-4725 1625);
PAINT WHITE (-4725 1625);
DISPLAY INVISIBLE (-4725 1625);
FORCEPROP 2 LAST ROOM SB_DECOUPLING
J 0
(-4775 1475);
PAINT WHITE (-4775 1475);
DISPLAY INVISIBLE (-4775 1475);
FORCEADD CAP_A..1
(-5200 1475);
FORCEPROP 1 LAST LOCATION C3N22
J 0
(-5150 1575);
DISPLAY 0.617021 (-5150 1575);
PAINT AQUA (-5150 1575);
FORCEPROP 1 LAST PART_NUMBER D97712-004
J 0
(-5150 1325);
DISPLAY 0.617021 (-5150 1325);
PAINT BLUE (-5150 1325);
FORCEPROP 1 LAST VALUE 1.0UF
J 0
(-5150 1525);
DISPLAY 0.617021 (-5150 1525);
PAINT SKYBLUE (-5150 1525);
FORCEPROP 1 LAST TOLERANCE 10%
J 0
(-5150 1425);
DISPLAY 0.617021 (-5150 1425);
PAINT SKYBLUE (-5150 1425);
FORCEPROP 1 LAST PACK_TYPE 0402V
J 0
(-5150 1275);
DISPLAY 0.617021 (-5150 1275);
PAINT SKYBLUE (-5150 1275);
FORCEPROP 1 LAST VOLTAGE 6.3V
J 0
(-5150 1475);
DISPLAY 0.617021 (-5150 1475);
PAINT SKYBLUE (-5150 1475);
FORCEPROP 1 LAST MATERIAL X6S
J 0
(-5150 1375);
DISPLAY 0.617021 (-5150 1375);
PAINT SKYBLUE (-5150 1375);
FORCEPROP 1 LASTPIN (-5200 1575) $PN 1
J 0
(-5190 1555);
DISPLAY 0.617021 (-5190 1555);
PAINT WHITE (-5190 1555);
FORCEPROP 1 LASTPIN (-5200 1375) $PN 2
J 0
(-5190 1355);
DISPLAY 0.617021 (-5190 1355);
PAINT WHITE (-5190 1355);
FORCEPROP 2 LAST CDS_LOCATION C3N22
J 0
(-5150 1575);
DISPLAY 0.617021 (-5150 1575);
PAINT AQUA (-5150 1575);
DISPLAY INVISIBLE (-5150 1575);
FORCEPROP 2 LAST BOM_COST SB
J 0
(-5150 1225);
PAINT MONO (-5150 1225);
DISPLAY INVISIBLE (-5150 1225);
FORCEPROP 2 LAST CDS_LIB dev_discrete
J 0
(-5200 1475);
PAINT ORANGE (-5200 1475);
DISPLAY INVISIBLE (-5200 1475);
FORCEPROP 2 LAST CDS_SEC 1
J 0
(-5150 1675);
PAINT MONO (-5150 1675);
DISPLAY INVISIBLE (-5150 1675);
FORCEPROP 2 LAST $SEC 1
J 0
(-5150 1675);
PAINT MONO (-5150 1675);
DISPLAY INVISIBLE (-5150 1675);
FORCEPROP 1 LAST PATH I53
J 0
(-5150 1625);
DISPLAY 0.978723 (-5150 1625);
PAINT WHITE (-5150 1625);
DISPLAY INVISIBLE (-5150 1625);
FORCEPROP 2 LAST ROOM SB_DECOUPLING
J 0
(-5200 1475);
PAINT WHITE (-5200 1475);
DISPLAY INVISIBLE (-5200 1475);
FORCEADD P3V3_STBY..1
(-4325 5175);
FORCEPROP 3 LASTPIN (-4325 5125) SIG_NAME P3V3_STBY\g
J 0
(-4315 5135);
DISPLAY 0.659574 (-4315 5135);
PAINT MONO (-4315 5135);
DISPLAY INVISIBLE (-4315 5135);
FORCEPROP 1 LAST VOLTAGE 3.3V
J 0
(-4370 5132);
DISPLAY 0.340426 (-4370 5132);
PAINT SKYBLUE (-4370 5132);
DISPLAY INVISIBLE (-4370 5132);
FORCEPROP 2 LAST CDS_LIB mstr_symbols
J 0
(-4325 5175);
PAINT ORANGE (-4325 5175);
DISPLAY INVISIBLE (-4325 5175);
FORCEPROP 1 LAST SIZE 1B
J 0
(-4280 5197);
DISPLAY 0.340426 (-4280 5197);
PAINT GREEN (-4280 5197);
DISPLAY INVISIBLE (-4280 5197);
FORCEPROP 1 LAST BODY_TYPE PLUMBING
J 0
(-4370 5132);
DISPLAY 0.340426 (-4370 5132);
PAINT GREEN (-4370 5132);
DISPLAY INVISIBLE (-4370 5132);
FORCEPROP 1 LAST PATH I54
J 0
(-4280 5177);
DISPLAY 0.340426 (-4280 5177);
PAINT GREEN (-4280 5177);
DISPLAY INVISIBLE (-4280 5177);
FORCEPROP 1 LAST HDL_POWER P3V3_STBY
J 0
(-4625 5050);
DISPLAY 0.872340 (-4625 5050);
PAINT ORANGE (-4625 5050);
DISPLAY INVISIBLE (-4625 5050);
FORCEADD P3V3_STBY..1
(-4375 4250);
FORCEPROP 3 LASTPIN (-4375 4200) SIG_NAME P3V3_STBY\g
J 0
(-4365 4210);
DISPLAY 0.659574 (-4365 4210);
PAINT MONO (-4365 4210);
DISPLAY INVISIBLE (-4365 4210);
FORCEPROP 1 LAST VOLTAGE 3.3V
J 0
(-4420 4207);
DISPLAY 0.340426 (-4420 4207);
PAINT SKYBLUE (-4420 4207);
DISPLAY INVISIBLE (-4420 4207);
FORCEPROP 1 LAST SIZE 1B
J 0
(-4330 4272);
DISPLAY 0.340426 (-4330 4272);
PAINT GREEN (-4330 4272);
DISPLAY INVISIBLE (-4330 4272);
FORCEPROP 2 LAST CDS_LIB mstr_symbols
J 0
(-4375 4250);
PAINT ORANGE (-4375 4250);
DISPLAY INVISIBLE (-4375 4250);
FORCEPROP 1 LAST BODY_TYPE PLUMBING
J 0
(-4420 4207);
DISPLAY 0.340426 (-4420 4207);
PAINT GREEN (-4420 4207);
DISPLAY INVISIBLE (-4420 4207);
FORCEPROP 1 LAST PATH I55
J 0
(-4330 4252);
DISPLAY 0.340426 (-4330 4252);
PAINT GREEN (-4330 4252);
DISPLAY INVISIBLE (-4330 4252);
FORCEPROP 1 LAST HDL_POWER P3V3_STBY
J 0
(-4675 4125);
DISPLAY 0.872340 (-4675 4125);
PAINT ORANGE (-4675 4125);
DISPLAY INVISIBLE (-4675 4125);
FORCEADD P3V3_STBY..1
(-1475 4225);
FORCEPROP 3 LASTPIN (-1475 4175) SIG_NAME P3V3_STBY\g
J 0
(-1465 4185);
DISPLAY 0.659574 (-1465 4185);
PAINT MONO (-1465 4185);
DISPLAY INVISIBLE (-1465 4185);
FORCEPROP 1 LAST VOLTAGE 3.3V
J 0
(-1520 4182);
DISPLAY 0.340426 (-1520 4182);
PAINT SKYBLUE (-1520 4182);
DISPLAY INVISIBLE (-1520 4182);
FORCEPROP 1 LAST SIZE 1B
J 0
(-1430 4247);
DISPLAY 0.340426 (-1430 4247);
PAINT GREEN (-1430 4247);
DISPLAY INVISIBLE (-1430 4247);
FORCEPROP 2 LAST CDS_LIB mstr_symbols
J 0
(-1475 4225);
PAINT ORANGE (-1475 4225);
DISPLAY INVISIBLE (-1475 4225);
FORCEPROP 1 LAST BODY_TYPE PLUMBING
J 0
(-1520 4182);
DISPLAY 0.340426 (-1520 4182);
PAINT GREEN (-1520 4182);
DISPLAY INVISIBLE (-1520 4182);
FORCEPROP 1 LAST PATH I58
J 0
(-1430 4227);
DISPLAY 0.340426 (-1430 4227);
PAINT GREEN (-1430 4227);
DISPLAY INVISIBLE (-1430 4227);
FORCEPROP 1 LAST HDL_POWER P3V3_STBY
J 0
(-1775 4100);
DISPLAY 0.872340 (-1775 4100);
PAINT ORANGE (-1775 4100);
DISPLAY INVISIBLE (-1775 4100);
FORCEADD P3V3_STBY..1
(1125 5200);
FORCEPROP 3 LASTPIN (1125 5150) SIG_NAME P3V3_STBY\g
J 0
(1135 5160);
DISPLAY 0.659574 (1135 5160);
PAINT MONO (1135 5160);
DISPLAY INVISIBLE (1135 5160);
FORCEPROP 1 LAST VOLTAGE 3.3V
J 0
(1080 5157);
DISPLAY 0.340426 (1080 5157);
PAINT SKYBLUE (1080 5157);
DISPLAY INVISIBLE (1080 5157);
FORCEPROP 2 LAST CDS_LIB mstr_symbols
J 0
(1125 5200);
PAINT ORANGE (1125 5200);
DISPLAY INVISIBLE (1125 5200);
FORCEPROP 1 LAST SIZE 1B
J 0
(1170 5222);
DISPLAY 0.340426 (1170 5222);
PAINT GREEN (1170 5222);
DISPLAY INVISIBLE (1170 5222);
FORCEPROP 1 LAST BODY_TYPE PLUMBING
J 0
(1080 5157);
DISPLAY 0.340426 (1080 5157);
PAINT GREEN (1080 5157);
DISPLAY INVISIBLE (1080 5157);
FORCEPROP 1 LAST PATH I59
J 0
(1170 5202);
DISPLAY 0.340426 (1170 5202);
PAINT GREEN (1170 5202);
DISPLAY INVISIBLE (1170 5202);
FORCEPROP 1 LAST HDL_POWER P3V3_STBY
J 0
(825 5075);
DISPLAY 0.872340 (825 5075);
PAINT ORANGE (825 5075);
DISPLAY INVISIBLE (825 5075);
FORCEADD GND..1
(1175 3600);
FORCEPROP 3 LASTPIN (1175 3650) SIG_NAME GND\g
J 0
(1185 3660);
DISPLAY 0.659574 (1185 3660);
PAINT MONO (1185 3660);
DISPLAY INVISIBLE (1185 3660);
FORCEPROP 1 LAST VOLTAGE 0
J 0
(1175 3600);
PAINT SKYBLUE (1175 3600);
DISPLAY INVISIBLE (1175 3600);
FORCEPROP 2 LAST BOM_COST SB
J 0
(1125 3675);
PAINT MONO (1125 3675);
DISPLAY INVISIBLE (1125 3675);
FORCEPROP 1 LAST SIZE 1B
J 0
(1250 3550);
DISPLAY 1.404255 (1250 3550);
PAINT GREEN (1250 3550);
DISPLAY INVISIBLE (1250 3550);
FORCEPROP 2 LAST CDS_LIB mstr_symbols
J 0
(1175 3600);
PAINT ORANGE (1175 3600);
DISPLAY INVISIBLE (1175 3600);
FORCEPROP 1 LAST BODY_TYPE PLUMBING
J 0
(1130 3557);
DISPLAY 0.340426 (1130 3557);
PAINT GREEN (1130 3557);
DISPLAY INVISIBLE (1130 3557);
FORCEPROP 1 LAST PATH I6
J 0
(1250 3600);
DISPLAY 0.872340 (1250 3600);
PAINT AQUA (1250 3600);
DISPLAY INVISIBLE (1250 3600);
FORCEPROP 2 LAST ROOM SB_DECOUPLING
J 0
(700 3675);
PAINT WHITE (700 3675);
DISPLAY INVISIBLE (700 3675);
FORCEPROP 1 LAST HDL_POWER GND
J 0
(1175 3750);
DISPLAY 1.404255 (1175 3750);
PAINT GREEN (1175 3750);
DISPLAY INVISIBLE (1175 3750);
FORCEADD P3V3_STBY..1
(1175 4175);
FORCEPROP 3 LASTPIN (1175 4125) SIG_NAME P3V3_STBY\g
J 0
(1185 4135);
DISPLAY 0.659574 (1185 4135);
PAINT MONO (1185 4135);
DISPLAY INVISIBLE (1185 4135);
FORCEPROP 1 LAST VOLTAGE 3.3V
J 0
(1130 4132);
DISPLAY 0.340426 (1130 4132);
PAINT SKYBLUE (1130 4132);
DISPLAY INVISIBLE (1130 4132);
FORCEPROP 2 LAST CDS_LIB mstr_symbols
J 0
(1175 4175);
PAINT ORANGE (1175 4175);
DISPLAY INVISIBLE (1175 4175);
FORCEPROP 1 LAST SIZE 1B
J 0
(1220 4197);
DISPLAY 0.340426 (1220 4197);
PAINT GREEN (1220 4197);
DISPLAY INVISIBLE (1220 4197);
FORCEPROP 1 LAST BODY_TYPE PLUMBING
J 0
(1130 4132);
DISPLAY 0.340426 (1130 4132);
PAINT GREEN (1130 4132);
DISPLAY INVISIBLE (1130 4132);
FORCEPROP 1 LAST PATH I60
J 0
(1220 4177);
DISPLAY 0.340426 (1220 4177);
PAINT GREEN (1220 4177);
DISPLAY INVISIBLE (1220 4177);
FORCEPROP 1 LAST HDL_POWER P3V3_STBY
J 0
(875 4050);
DISPLAY 0.872340 (875 4050);
PAINT ORANGE (875 4050);
DISPLAY INVISIBLE (875 4050);
FORCEADD P3V3_STBY..1
(650 2925);
FORCEPROP 3 LASTPIN (650 2875) SIG_NAME P3V3_STBY\g
J 0
(660 2885);
DISPLAY 0.659574 (660 2885);
PAINT MONO (660 2885);
DISPLAY INVISIBLE (660 2885);
FORCEPROP 1 LAST VOLTAGE 3.3V
J 0
(605 2882);
DISPLAY 0.340426 (605 2882);
PAINT SKYBLUE (605 2882);
DISPLAY INVISIBLE (605 2882);
FORCEPROP 2 LAST CDS_LIB mstr_symbols
J 0
(650 2925);
PAINT ORANGE (650 2925);
DISPLAY INVISIBLE (650 2925);
FORCEPROP 1 LAST SIZE 1B
J 0
(695 2947);
DISPLAY 0.340426 (695 2947);
PAINT GREEN (695 2947);
DISPLAY INVISIBLE (695 2947);
FORCEPROP 1 LAST BODY_TYPE PLUMBING
J 0
(605 2882);
DISPLAY 0.340426 (605 2882);
PAINT GREEN (605 2882);
DISPLAY INVISIBLE (605 2882);
FORCEPROP 1 LAST PATH I61
J 0
(695 2927);
DISPLAY 0.340426 (695 2927);
PAINT GREEN (695 2927);
DISPLAY INVISIBLE (695 2927);
FORCEPROP 1 LAST HDL_POWER P3V3_STBY
J 0
(350 2800);
DISPLAY 0.872340 (350 2800);
PAINT ORANGE (350 2800);
DISPLAY INVISIBLE (350 2800);
FORCEADD P3V3_STBY..1
(1925 1875);
FORCEPROP 3 LASTPIN (1925 1825) SIG_NAME P3V3_STBY\g
J 0
(1935 1835);
DISPLAY 0.659574 (1935 1835);
PAINT MONO (1935 1835);
DISPLAY INVISIBLE (1935 1835);
FORCEPROP 1 LAST VOLTAGE 3.3V
J 0
(1880 1832);
DISPLAY 0.340426 (1880 1832);
PAINT SKYBLUE (1880 1832);
DISPLAY INVISIBLE (1880 1832);
FORCEPROP 2 LAST CDS_LIB mstr_symbols
J 0
(1925 1875);
PAINT ORANGE (1925 1875);
DISPLAY INVISIBLE (1925 1875);
FORCEPROP 1 LAST SIZE 1B
J 0
(1970 1897);
DISPLAY 0.340426 (1970 1897);
PAINT GREEN (1970 1897);
DISPLAY INVISIBLE (1970 1897);
FORCEPROP 1 LAST BODY_TYPE PLUMBING
J 0
(1880 1832);
DISPLAY 0.340426 (1880 1832);
PAINT GREEN (1880 1832);
DISPLAY INVISIBLE (1880 1832);
FORCEPROP 1 LAST PATH I62
J 0
(1970 1877);
DISPLAY 0.340426 (1970 1877);
PAINT GREEN (1970 1877);
DISPLAY INVISIBLE (1970 1877);
FORCEPROP 1 LAST HDL_POWER P3V3_STBY
J 0
(1625 1750);
DISPLAY 0.872340 (1625 1750);
PAINT ORANGE (1625 1750);
DISPLAY INVISIBLE (1625 1750);
FORCEADD CAP_A..1
(1175 3900);
FORCEPROP 1 LAST LOCATION C2N19
J 0
(1225 4000);
DISPLAY 0.617021 (1225 4000);
PAINT AQUA (1225 4000);
FORCEPROP 1 LAST PART_NUMBER D97712-004
J 0
(1225 3750);
DISPLAY 0.617021 (1225 3750);
PAINT BLUE (1225 3750);
FORCEPROP 1 LAST VALUE 1.0UF
J 0
(1225 3950);
DISPLAY 0.617021 (1225 3950);
PAINT SKYBLUE (1225 3950);
FORCEPROP 1 LAST TOLERANCE 10%
J 0
(1225 3850);
DISPLAY 0.617021 (1225 3850);
PAINT SKYBLUE (1225 3850);
FORCEPROP 1 LAST PACK_TYPE 0402V
J 0
(1225 3700);
DISPLAY 0.617021 (1225 3700);
PAINT SKYBLUE (1225 3700);
FORCEPROP 1 LAST VOLTAGE 6.3V
J 0
(1225 3900);
DISPLAY 0.617021 (1225 3900);
PAINT SKYBLUE (1225 3900);
FORCEPROP 1 LAST MATERIAL X6S
J 0
(1225 3800);
DISPLAY 0.617021 (1225 3800);
PAINT SKYBLUE (1225 3800);
FORCEPROP 1 LASTPIN (1175 4000) $PN 1
J 0
(1185 3980);
DISPLAY 0.617021 (1185 3980);
PAINT WHITE (1185 3980);
FORCEPROP 1 LASTPIN (1175 3800) $PN 2
J 0
(1185 3780);
DISPLAY 0.617021 (1185 3780);
PAINT WHITE (1185 3780);
FORCEPROP 2 LAST CDS_LOCATION C2N19
J 0
(1225 4000);
DISPLAY 0.617021 (1225 4000);
PAINT AQUA (1225 4000);
DISPLAY INVISIBLE (1225 4000);
FORCEPROP 2 LAST BOM_COST SB
J 0
(1225 3650);
PAINT MONO (1225 3650);
DISPLAY INVISIBLE (1225 3650);
FORCEPROP 2 LAST CDS_LIB dev_discrete
J 0
(1175 3900);
PAINT ORANGE (1175 3900);
DISPLAY INVISIBLE (1175 3900);
FORCEPROP 2 LAST CDS_SEC 1
J 0
(1225 4100);
DISPLAY 1.361702 (1225 4100);
PAINT ORANGE (1225 4100);
DISPLAY INVISIBLE (1225 4100);
FORCEPROP 2 LAST $SEC 1
J 0
(1225 4100);
DISPLAY 0.914894 (1225 4100);
PAINT MONO (1225 4100);
DISPLAY INVISIBLE (1225 4100);
FORCEPROP 1 LAST PATH I7
J 0
(1225 4050);
DISPLAY 0.978723 (1225 4050);
PAINT WHITE (1225 4050);
DISPLAY INVISIBLE (1225 4050);
FORCEPROP 2 LAST ROOM SB_DECOUPLING
J 0
(1175 3900);
PAINT WHITE (1175 3900);
DISPLAY INVISIBLE (1175 3900);
FORCEADD CAP..1
(1300 2650);
FORCEPROP 1 LAST LOCATION C2N24
J 0
(1350 2750);
DISPLAY 0.617021 (1350 2750);
PAINT AQUA (1350 2750);
FORCEPROP 1 LAST PART_NUMBER E15431-002
J 0
(1350 2500);
DISPLAY 0.617021 (1350 2500);
PAINT BLUE (1350 2500);
FORCEPROP 1 LAST VALUE 10UF
J 0
(1350 2700);
DISPLAY 0.617021 (1350 2700);
PAINT SKYBLUE (1350 2700);
FORCEPROP 1 LAST TOLERANCE 20%
J 0
(1350 2600);
DISPLAY 0.617021 (1350 2600);
PAINT SKYBLUE (1350 2600);
FORCEPROP 1 LAST PACK_TYPE 0603
J 0
(1350 2450);
DISPLAY 0.617021 (1350 2450);
PAINT SKYBLUE (1350 2450);
FORCEPROP 1 LAST VOLTAGE 6.3V
J 0
(1350 2650);
DISPLAY 0.617021 (1350 2650);
PAINT SKYBLUE (1350 2650);
FORCEPROP 1 LAST MATERIAL X6S
J 0
(1350 2550);
DISPLAY 0.617021 (1350 2550);
PAINT SKYBLUE (1350 2550);
FORCEPROP 1 LASTPIN (1300 2550) $PN 2
J 0
(1310 2530);
DISPLAY 0.617021 (1310 2530);
PAINT WHITE (1310 2530);
FORCEPROP 1 LASTPIN (1300 2750) $PN 1
J 0
(1310 2730);
DISPLAY 0.617021 (1310 2730);
PAINT WHITE (1310 2730);
FORCEPROP 2 LAST CDS_LIB mstr_discrete
J 0
(1300 2650);
PAINT ORANGE (1300 2650);
DISPLAY INVISIBLE (1300 2650);
FORCEPROP 2 LAST BOM_COST SB
J 0
(1350 2400);
PAINT MONO (1350 2400);
DISPLAY INVISIBLE (1350 2400);
FORCEPROP 2 LAST CDS_SEC 1
J 0
(1350 2850);
DISPLAY 1.361702 (1350 2850);
PAINT ORANGE (1350 2850);
DISPLAY INVISIBLE (1350 2850);
FORCEPROP 2 LAST $SEC 1
J 0
(1350 2850);
DISPLAY 0.914894 (1350 2850);
PAINT MONO (1350 2850);
DISPLAY INVISIBLE (1350 2850);
FORCEPROP 2 LAST CDS_LOCATION C2N24
J 0
(1350 2750);
DISPLAY 0.617021 (1350 2750);
PAINT AQUA (1350 2750);
DISPLAY INVISIBLE (1350 2750);
FORCEPROP 1 LAST PATH I8
J 0
(1350 2800);
DISPLAY 0.978723 (1350 2800);
PAINT WHITE (1350 2800);
DISPLAY INVISIBLE (1350 2800);
FORCEPROP 2 LAST ROOM SB_DECOUPLING
J 0
(1300 2650);
PAINT WHITE (1300 2650);
DISPLAY INVISIBLE (1300 2650);
FORCEADD CAP..1
(875 2650);
FORCEPROP 1 LAST LOCATION C2N22
J 0
(925 2750);
DISPLAY 0.617021 (925 2750);
PAINT AQUA (925 2750);
FORCEPROP 1 LAST PART_NUMBER E15431-002
J 0
(925 2500);
DISPLAY 0.617021 (925 2500);
PAINT BLUE (925 2500);
FORCEPROP 1 LAST VALUE 10UF
J 0
(925 2700);
DISPLAY 0.617021 (925 2700);
PAINT SKYBLUE (925 2700);
FORCEPROP 1 LAST TOLERANCE 20%
J 0
(925 2600);
DISPLAY 0.617021 (925 2600);
PAINT SKYBLUE (925 2600);
FORCEPROP 1 LAST PACK_TYPE 0603
J 0
(925 2450);
DISPLAY 0.617021 (925 2450);
PAINT SKYBLUE (925 2450);
FORCEPROP 1 LAST VOLTAGE 6.3V
J 0
(925 2650);
DISPLAY 0.617021 (925 2650);
PAINT SKYBLUE (925 2650);
FORCEPROP 1 LAST MATERIAL X6S
J 0
(925 2550);
DISPLAY 0.617021 (925 2550);
PAINT SKYBLUE (925 2550);
FORCEPROP 1 LASTPIN (875 2550) $PN 2
J 0
(885 2530);
DISPLAY 0.617021 (885 2530);
PAINT WHITE (885 2530);
FORCEPROP 1 LASTPIN (875 2750) $PN 1
J 0
(885 2730);
DISPLAY 0.617021 (885 2730);
PAINT WHITE (885 2730);
FORCEPROP 2 LAST CDS_LIB mstr_discrete
J 0
(875 2650);
PAINT ORANGE (875 2650);
DISPLAY INVISIBLE (875 2650);
FORCEPROP 2 LAST BOM_COST SB
J 0
(925 2400);
PAINT MONO (925 2400);
DISPLAY INVISIBLE (925 2400);
FORCEPROP 2 LAST CDS_SEC 1
J 0
(925 2850);
DISPLAY 1.361702 (925 2850);
PAINT ORANGE (925 2850);
DISPLAY INVISIBLE (925 2850);
FORCEPROP 2 LAST $SEC 1
J 0
(925 2850);
DISPLAY 0.914894 (925 2850);
PAINT MONO (925 2850);
DISPLAY INVISIBLE (925 2850);
FORCEPROP 2 LAST CDS_LOCATION C2N22
J 0
(925 2750);
DISPLAY 0.617021 (925 2750);
PAINT AQUA (925 2750);
DISPLAY INVISIBLE (925 2750);
FORCEPROP 1 LAST PATH I9
J 0
(925 2800);
DISPLAY 0.978723 (925 2800);
PAINT WHITE (925 2800);
DISPLAY INVISIBLE (925 2800);
FORCEPROP 2 LAST ROOM SB_DECOUPLING
J 0
(875 2650);
PAINT WHITE (875 2650);
DISPLAY INVISIBLE (875 2650);
FORCEADD CAD_NOTE..1
(-2525 3625);
FORCEPROP 0 LAST L1 PLACE CAPS BSC
J 0
(-2675 3500);
DISPLAY 1.063830 (-2675 3500);
PAINT WHITE (-2675 3500);
FORCEPROP 0 LAST L2 STYLE NEAR TO PIN
J 0
(-2675 3425);
DISPLAY 1.063830 (-2675 3425);
PAINT WHITE (-2675 3425);
FORCEPROP 2 LAST BOM_COST SB
J 0
(-2675 3575);
PAINT MONO (-2675 3575);
DISPLAY INVISIBLE (-2675 3575);
FORCEPROP 2 LAST CDS_LIB mstr_symbols
J 0
(-2525 3625);
PAINT ORANGE (-2525 3625);
DISPLAY INVISIBLE (-2525 3625);
FORCEPROP 1 LAST COMMENT_BODY TRUE
J 0
(-2500 3725);
DISPLAY 1.319149 (-2500 3725);
PAINT GREEN (-2500 3725);
DISPLAY INVISIBLE (-2500 3725);
FORCEPROP 2 LAST ROOM SB_DECOUPLING
J 0
(-2675 3575);
PAINT WHITE (-2675 3575);
DISPLAY INVISIBLE (-2675 3575);
FORCEADD CAD_NOTE..1
(1775 4225);
FORCEPROP 0 LAST L2 STYLE NEAR TO PIN.
J 0
(1625 4025);
DISPLAY 1.063830 (1625 4025);
PAINT WHITE (1625 4025);
FORCEPROP 0 LAST L1 PLACE CAPS BSC
J 0
(1625 4100);
DISPLAY 1.063830 (1625 4100);
PAINT WHITE (1625 4100);
FORCEPROP 2 LAST CDS_LIB mstr_symbols
J 0
(1775 4225);
PAINT ORANGE (1775 4225);
DISPLAY INVISIBLE (1775 4225);
FORCEPROP 2 LAST BOM_COST SB
J 0
(1625 4175);
PAINT MONO (1625 4175);
DISPLAY INVISIBLE (1625 4175);
FORCEPROP 1 LAST COMMENT_BODY TRUE
J 0
(1800 4325);
DISPLAY 1.319149 (1800 4325);
PAINT GREEN (1800 4325);
DISPLAY INVISIBLE (1800 4325);
FORCEPROP 2 LAST ROOM SB_DECOUPLING
J 0
(1625 4175);
PAINT WHITE (1625 4175);
DISPLAY INVISIBLE (1625 4175);
FORCEADD CAD_NOTE..1
(1750 5175);
FORCEPROP 0 LAST L2 EDGE OF THE PKG.
J 0
(1600 4975);
DISPLAY 1.063830 (1600 4975);
PAINT WHITE (1600 4975);
FORCEPROP 0 LAST L1 PLACE CAPS ON THE
J 0
(1600 5050);
DISPLAY 1.063830 (1600 5050);
PAINT WHITE (1600 5050);
FORCEPROP 2 LAST BOM_COST SB
J 0
(1600 5125);
PAINT MONO (1600 5125);
DISPLAY INVISIBLE (1600 5125);
FORCEPROP 2 LAST CDS_LIB mstr_symbols
J 0
(1750 5175);
PAINT ORANGE (1750 5175);
DISPLAY INVISIBLE (1750 5175);
FORCEPROP 1 LAST COMMENT_BODY TRUE
J 0
(1775 5275);
DISPLAY 1.319149 (1775 5275);
PAINT GREEN (1775 5275);
DISPLAY INVISIBLE (1775 5275);
FORCEPROP 2 LAST ROOM SB_DECOUPLING
J 0
(1600 5125);
PAINT WHITE (1600 5125);
DISPLAY INVISIBLE (1600 5125);
FORCEADD CAD_NOTE..1
(1775 2200);
FORCEPROP 0 LAST L2 STYLE NEAR TO PIN.
J 0
(1625 2000);
DISPLAY 1.063830 (1625 2000);
PAINT WHITE (1625 2000);
FORCEPROP 0 LAST L1 PLACE CAPS BSC
J 0
(1625 2075);
DISPLAY 1.063830 (1625 2075);
PAINT WHITE (1625 2075);
FORCEPROP 2 LAST BOM_COST SB
J 0
(1625 2150);
PAINT MONO (1625 2150);
DISPLAY INVISIBLE (1625 2150);
FORCEPROP 2 LAST CDS_LIB mstr_symbols
J 0
(1775 2200);
PAINT ORANGE (1775 2200);
DISPLAY INVISIBLE (1775 2200);
FORCEPROP 1 LAST COMMENT_BODY TRUE
J 0
(1800 2300);
DISPLAY 1.319149 (1800 2300);
PAINT GREEN (1800 2300);
DISPLAY INVISIBLE (1800 2300);
FORCEPROP 2 LAST ROOM SB_DECOUPLING
J 0
(1625 2150);
PAINT WHITE (1625 2150);
DISPLAY INVISIBLE (1625 2150);
FORCEADD DESIGN_NOTE..1
(-925 2725);
FORCEPROP 0 LAST L1 VCCRTCEXT: RTC DECOUPLING
J 0
(-1125 2600);
DISPLAY 1.063830 (-1125 2600);
PAINT WHITE (-1125 2600);
FORCEPROP 0 LAST L3 BE DRIVEN
J 0
(-1125 2450);
DISPLAY 1.085106 (-1125 2450);
PAINT WHITE (-1125 2450);
FORCEPROP 0 LAST L2 CAP ONLY, PIN SHOULD NOT
J 0
(-1125 2525);
DISPLAY 1.063830 (-1125 2525);
PAINT WHITE (-1125 2525);
FORCEPROP 2 LAST CDS_LIB mstr_symbols
J 0
(-925 2725);
PAINT ORANGE (-925 2725);
DISPLAY INVISIBLE (-925 2725);
FORCEPROP 2 LAST BOM_COST SB
J 0
(-1125 2650);
DISPLAY 1.361702 (-1125 2650);
PAINT ORANGE (-1125 2650);
DISPLAY INVISIBLE (-1125 2650);
FORCEPROP 1 LAST COMMENT_BODY TRUE
J 0
(-900 2825);
DISPLAY 1.319149 (-900 2825);
PAINT ORANGE (-900 2825);
DISPLAY INVISIBLE (-900 2825);
FORCEPROP 2 LAST ROOM SB_DECOUPLING
J 0
(-1125 2650);
DISPLAY 1.361702 (-1125 2650);
PAINT WHITE (-1125 2650);
DISPLAY INVISIBLE (-1125 2650);
FORCEADD DESIGN_NOTE..1
(-1950 1300);
FORCEPROP 0 LAST L1 P1V8_PCH_STBY
J 0
(-2150 1175);
DISPLAY 1.063830 (-2150 1175);
PAINT WHITE (-2150 1175);
FORCEPROP 0 LAST L2 DECOUPLING CAPS
J 0
(-2150 1100);
DISPLAY 1.063830 (-2150 1100);
PAINT WHITE (-2150 1100);
FORCEPROP 2 LAST CDS_LIB mstr_symbols
J 0
(-1950 1300);
PAINT ORANGE (-1950 1300);
DISPLAY INVISIBLE (-1950 1300);
FORCEPROP 2 LAST BOM_COST SB
J 0
(-2150 1225);
DISPLAY 1.361702 (-2150 1225);
PAINT ORANGE (-2150 1225);
DISPLAY INVISIBLE (-2150 1225);
FORCEPROP 1 LAST COMMENT_BODY TRUE
J 0
(-1925 1400);
DISPLAY 1.319149 (-1925 1400);
PAINT ORANGE (-1925 1400);
DISPLAY INVISIBLE (-1925 1400);
FORCEPROP 2 LAST ROOM SB_DECOUPLING
J 0
(-2150 1225);
DISPLAY 1.361702 (-2150 1225);
PAINT WHITE (-2150 1225);
DISPLAY INVISIBLE (-2150 1225);
FORCEADD DESIGN_NOTE..1
(-1200 3525);
FORCEPROP 0 LAST L1 P3V3_STBY DECOUPLING CAPS
J 0
(-1400 3400);
DISPLAY 1.063830 (-1400 3400);
PAINT WHITE (-1400 3400);
FORCEPROP 2 LAST BOM_COST SB
J 0
(-1400 3450);
DISPLAY 1.361702 (-1400 3450);
PAINT ORANGE (-1400 3450);
DISPLAY INVISIBLE (-1400 3450);
FORCEPROP 2 LAST CDS_LIB mstr_symbols
J 0
(-1200 3525);
PAINT ORANGE (-1200 3525);
DISPLAY INVISIBLE (-1200 3525);
FORCEPROP 1 LAST COMMENT_BODY TRUE
J 0
(-1175 3625);
DISPLAY 1.319149 (-1175 3625);
PAINT ORANGE (-1175 3625);
DISPLAY INVISIBLE (-1175 3625);
FORCEPROP 2 LAST ROOM SB_DECOUPLING
J 0
(-1400 3450);
DISPLAY 1.361702 (-1400 3450);
PAINT WHITE (-1400 3450);
DISPLAY INVISIBLE (-1400 3450);
FORCEADD CAD_NOTE..1
(-1900 5025);
FORCEPROP 0 LAST L1 PLACE CAPS ON THE
J 0
(-2050 4900);
DISPLAY 1.063830 (-2050 4900);
PAINT WHITE (-2050 4900);
FORCEPROP 0 LAST L2 EDGE OF THE PKG.
J 0
(-2050 4825);
DISPLAY 1.063830 (-2050 4825);
PAINT WHITE (-2050 4825);
FORCEPROP 2 LAST BOM_COST SB
J 0
(-2050 4975);
PAINT MONO (-2050 4975);
DISPLAY INVISIBLE (-2050 4975);
FORCEPROP 2 LAST CDS_LIB mstr_symbols
J 0
(-1900 5025);
PAINT ORANGE (-1900 5025);
DISPLAY INVISIBLE (-1900 5025);
FORCEPROP 1 LAST COMMENT_BODY TRUE
J 0
(-1875 5125);
DISPLAY 1.319149 (-1875 5125);
PAINT GREEN (-1875 5125);
DISPLAY INVISIBLE (-1875 5125);
FORCEPROP 2 LAST ROOM SB_DECOUPLING
J 0
(-2050 4975);
PAINT WHITE (-2050 4975);
DISPLAY INVISIBLE (-2050 4975);
FORCEADD CAD_NOTE..1
(-2425 2850);
FORCEPROP 0 LAST L1 PLACE CAPS ON THE
J 0
(-2575 2725);
DISPLAY 1.063830 (-2575 2725);
PAINT WHITE (-2575 2725);
FORCEPROP 0 LAST L2 EDGE OF THE PKG.
J 0
(-2575 2650);
DISPLAY 1.063830 (-2575 2650);
PAINT WHITE (-2575 2650);
FORCEPROP 2 LAST CDS_LIB mstr_symbols
J 0
(-2425 2850);
PAINT ORANGE (-2425 2850);
DISPLAY INVISIBLE (-2425 2850);
FORCEPROP 2 LAST BOM_COST SB
J 0
(-2575 2800);
PAINT MONO (-2575 2800);
DISPLAY INVISIBLE (-2575 2800);
FORCEPROP 1 LAST COMMENT_BODY TRUE
J 0
(-2400 2950);
DISPLAY 1.319149 (-2400 2950);
PAINT GREEN (-2400 2950);
DISPLAY INVISIBLE (-2400 2950);
FORCEPROP 2 LAST ROOM SB_DECOUPLING
J 0
(-2575 2800);
PAINT WHITE (-2575 2800);
DISPLAY INVISIBLE (-2575 2800);
FORCEADD DESIGN_NOTE..1
(700 1800);
FORCEPROP 0 LAST L2 DECOUPLING CAPS
J 0
(500 1600);
DISPLAY 1.063830 (500 1600);
PAINT WHITE (500 1600);
FORCEPROP 0 LAST L1 P3V3_DSW
J 0
(500 1675);
DISPLAY 1.063830 (500 1675);
PAINT WHITE (500 1675);
FORCEPROP 2 LAST BOM_COST SB
J 0
(500 1725);
DISPLAY 1.361702 (500 1725);
PAINT ORANGE (500 1725);
DISPLAY INVISIBLE (500 1725);
FORCEPROP 2 LAST CDS_LIB mstr_symbols
J 0
(700 1800);
PAINT ORANGE (700 1800);
DISPLAY INVISIBLE (700 1800);
FORCEPROP 1 LAST COMMENT_BODY TRUE
J 0
(725 1900);
DISPLAY 1.319149 (725 1900);
PAINT ORANGE (725 1900);
DISPLAY INVISIBLE (725 1900);
FORCEPROP 2 LAST ROOM SB_DECOUPLING
J 0
(500 1725);
DISPLAY 1.361702 (500 1725);
PAINT WHITE (500 1725);
DISPLAY INVISIBLE (500 1725);
FORCEADD CAD_NOTE..1
(-950 1700);
FORCEPROP 0 LAST L2 NEAR TO PIN.
J 0
(-1100 1500);
DISPLAY 1.063830 (-1100 1500);
PAINT WHITE (-1100 1500);
FORCEPROP 0 LAST L1 PLACE CAP
J 0
(-1100 1575);
DISPLAY 1.063830 (-1100 1575);
PAINT WHITE (-1100 1575);
FORCEPROP 2 LAST CDS_LIB mstr_symbols
J 0
(-950 1700);
PAINT ORANGE (-950 1700);
DISPLAY INVISIBLE (-950 1700);
FORCEPROP 2 LAST BOM_COST SB
J 0
(-1100 1650);
PAINT MONO (-1100 1650);
DISPLAY INVISIBLE (-1100 1650);
FORCEPROP 1 LAST COMMENT_BODY TRUE
J 0
(-925 1800);
DISPLAY 1.319149 (-925 1800);
PAINT GREEN (-925 1800);
DISPLAY INVISIBLE (-925 1800);
FORCEPROP 2 LAST ROOM SB_DECOUPLING
J 0
(-1100 1650);
PAINT WHITE (-1100 1650);
DISPLAY INVISIBLE (-1100 1650);
FORCEADD CAD_NOTE..1
(-3100 1225);
FORCEPROP 0 LAST L1 PLACE CAPS BSC
J 0
(-3250 1100);
DISPLAY 1.063830 (-3250 1100);
PAINT WHITE (-3250 1100);
FORCEPROP 0 LAST L2 STYLE NEAR TO PIN.
J 0
(-3250 1025);
DISPLAY 1.063830 (-3250 1025);
PAINT WHITE (-3250 1025);
FORCEPROP 2 LAST CDS_LIB mstr_symbols
J 0
(-3100 1225);
PAINT ORANGE (-3100 1225);
DISPLAY INVISIBLE (-3100 1225);
FORCEPROP 2 LAST BOM_COST SB
J 0
(-3250 1175);
PAINT MONO (-3250 1175);
DISPLAY INVISIBLE (-3250 1175);
FORCEPROP 1 LAST COMMENT_BODY TRUE
J 0
(-3075 1325);
DISPLAY 1.319149 (-3075 1325);
PAINT GREEN (-3075 1325);
DISPLAY INVISIBLE (-3075 1325);
FORCEPROP 2 LAST ROOM SB_DECOUPLING
J 0
(-3250 1175);
PAINT WHITE (-3250 1175);
DISPLAY INVISIBLE (-3250 1175);
FORCEADD INTEL_CORP_BPAGE..1
(2600 525);
FORCEPROP 1 LAST CDS_CON_LAST_MODIFIED Fri Jun 16 17:48:50 2017
J 0
(1175 850);
PAINT ORANGE (1175 850);
DISPLAY INVISIBLE (1175 850);
FORCEPROP 1 LAST CUSTOM_TXT_CDS <CURRENT_DESIGN_SHEET> OF <TOTAL_DESIGN_SHEETS>
J 0
(2100 550);
PAINT ORANGE (2100 550);
FORCEPROP 1 LAST CUSTOM_TXT_CDS <CON_LAST_MODIFIED>
J 0
(-1400 625);
PAINT ORANGE (-1400 625);
FORCEPROP 2 LAST CUSTOM_TXT_CDS <XR_PAGE_TITLE>
J 0
(-5290 5775);
DISPLAY 0.638298 (-5290 5775);
PAINT PINK (-5290 5775);
DISPLAY INVISIBLE (-5290 5775);
FORCEPROP 1 LAST SCH_TITLE PCH DECOUPLING 1/3
J 0
(-5350 575);
DISPLAY 1.212766 (-5350 575);
PAINT ORANGE (-5350 575);
FORCEPROP 2 LAST BOM_COST SB
J 0
(-5275 5825);
PAINT MONO (-5275 5825);
DISPLAY INVISIBLE (-5275 5825);
FORCEPROP 2 LAST PAGE_BORDER TRUE
J 0
(-5290 5775);
DISPLAY 0.851064 (-5290 5775);
PAINT PINK (-5290 5775);
DISPLAY INVISIBLE (-5290 5775);
FORCEPROP 2 LAST CDS_LIB mstr_symbols
J 0
(2600 525);
PAINT MONO (2600 525);
DISPLAY INVISIBLE (2600 525);
FORCEPROP 1 LAST COMMENT_BODY TRUE
J 0
(2612 537);
DISPLAY 0.468085 (2612 537);
PAINT GREEN (2612 537);
DISPLAY INVISIBLE (2612 537);
FORCEPROP 2 LAST ROOM WBG_DECOUPLING
J 0
(-5275 5825);
PAINT MONO (-5275 5825);
DISPLAY INVISIBLE (-5275 5825);
FORCEPROP 2 LAST CDS_XR_PAGE_TITLE CR-130 : @BASEBOARD_FAB2_LIB.BASEBOARD_FAB2(SCH_1):PAGE130
J 0
(-5290 5775);
DISPLAY 0.638298 (-5290 5775);
PAINT PINK (-5290 5775);
DISPLAY INVISIBLE (-5290 5775);
FORCEADD DESIGN_NOTE..1
(1875 3625);
FORCEPROP 0 LAST L2 DECOUPLING CAPS
J 0
(1675 3425);
DISPLAY 1.063830 (1675 3425);
PAINT WHITE (1675 3425);
FORCEPROP 0 LAST L1 P3V3_STBY
J 0
(1675 3500);
DISPLAY 1.063830 (1675 3500);
PAINT WHITE (1675 3500);
FORCEPROP 2 LAST CDS_LIB mstr_symbols
J 0
(1875 3625);
PAINT ORANGE (1875 3625);
DISPLAY INVISIBLE (1875 3625);
FORCEPROP 2 LAST BOM_COST SB
J 0
(1675 3550);
DISPLAY 1.361702 (1675 3550);
PAINT ORANGE (1675 3550);
DISPLAY INVISIBLE (1675 3550);
FORCEPROP 1 LAST COMMENT_BODY TRUE
J 0
(1900 3725);
DISPLAY 1.319149 (1900 3725);
PAINT ORANGE (1900 3725);
DISPLAY INVISIBLE (1900 3725);
FORCEPROP 2 LAST ROOM SB_DECOUPLING
J 0
(1675 3550);
DISPLAY 1.361702 (1675 3550);
PAINT WHITE (1675 3550);
DISPLAY INVISIBLE (1675 3550);
FORCEADD CAD_NOTE..1
(1700 3075);
FORCEPROP 0 LAST L2 EDGE OF THE PKG.
J 0
(1550 2875);
DISPLAY 1.063830 (1550 2875);
PAINT WHITE (1550 2875);
FORCEPROP 0 LAST L1 PLACE CAPS ON THE
J 0
(1550 2950);
DISPLAY 1.063830 (1550 2950);
PAINT WHITE (1550 2950);
FORCEPROP 2 LAST BOM_COST SB
J 0
(1550 3025);
PAINT MONO (1550 3025);
DISPLAY INVISIBLE (1550 3025);
FORCEPROP 2 LAST CDS_LIB mstr_symbols
J 0
(1700 3075);
PAINT ORANGE (1700 3075);
DISPLAY INVISIBLE (1700 3075);
FORCEPROP 1 LAST COMMENT_BODY TRUE
J 0
(1725 3175);
DISPLAY 1.319149 (1725 3175);
PAINT GREEN (1725 3175);
DISPLAY INVISIBLE (1725 3175);
FORCEPROP 2 LAST ROOM SB_DECOUPLING
J 0
(1550 3025);
PAINT WHITE (1550 3025);
DISPLAY INVISIBLE (1550 3025);
WIRE 16 -1 (1925 1350)(1925 1500);
WIRE 16 -1 (650 2425)(650 2400);
WIRE 16 -1 (650 2425)(875 2425);
WIRE 16 -1 (425 2425)(650 2425);
WIRE 16 -1 (425 2550)(425 2425);
WIRE 16 -1 (1300 2425)(875 2425);
WIRE 16 -1 (875 2550)(875 2425);
WIRE 16 -1 (1300 2425)(1725 2425);
WIRE 16 -1 (1300 2550)(1300 2425);
WIRE 16 -1 (1725 2550)(1725 2425);
WIRE 16 -1 (0 1775)(0 1925);
WIRE 16 -1 (-1475 3675)(-1475 3825);
WIRE 16 -1 (1125 4775)(1125 4903);
WIRE 16 -1 (-1975 2000)(-1975 2125);
WIRE 16 -1 (-1975 1625)(-1975 1800);
WIRE 16 -1 (-4325 4700)(-4325 4625);
WIRE 16 -1 (-4325 4700)(-4175 4700);
WIRE 16 -1 (-4575 4700)(-4325 4700);
WIRE 16 -1 (-4575 4825)(-4575 4700);
WIRE 16 -1 (-3775 4700)(-4175 4700);
WIRE 16 -1 (-4175 4825)(-4175 4700);
WIRE 16 -1 (-3375 4700)(-3775 4700);
WIRE 16 -1 (-3775 4825)(-3775 4700);
WIRE 16 -1 (-2975 4700)(-3375 4700);
WIRE 16 -1 (-3375 4825)(-3375 4700);
WIRE 16 -1 (-2550 4700)(-2975 4700);
WIRE 16 -1 (-2975 4825)(-2975 4700);
WIRE 16 -1 (-2550 4825)(-2550 4700);
WIRE 16 -1 (-4375 3700)(-4375 3625);
WIRE 16 -1 (-4375 3700)(-4200 3700);
WIRE 16 -1 (-4600 3700)(-4375 3700);
WIRE 16 -1 (-4600 3825)(-4600 3700);
WIRE 16 -1 (-3825 3700)(-4200 3700);
WIRE 16 -1 (-4200 3825)(-4200 3700);
WIRE 16 -1 (-3450 3700)(-3825 3700);
WIRE 16 -1 (-3825 3825)(-3825 3700);
WIRE 16 -1 (-3450 3825)(-3450 3700);
WIRE 16 -1 (-4850 2925)(-4850 2975);
WIRE 16 -1 (-4725 2925)(-4850 2925);
WIRE 16 -1 (-4850 2925)(-5150 2925);
WIRE 16 -1 (-5150 2850)(-5150 2925);
WIRE 16 -1 (-4350 2925)(-4725 2925);
WIRE 16 -1 (-4725 2850)(-4725 2925);
WIRE 16 -1 (-4350 2925)(-3925 2925);
WIRE 16 -1 (-4350 2850)(-4350 2925);
WIRE 16 -1 (-3925 2925)(-3525 2925);
WIRE 16 -1 (-3925 2850)(-3925 2925);
WIRE 16 -1 (-3100 2925)(-3525 2925);
WIRE 16 -1 (-3525 2850)(-3525 2925);
WIRE 16 -1 (-3100 2850)(-3100 2925);
WIRE 16 -1 (-4075 2525)(-4075 2475);
WIRE 16 -1 (-4075 2525)(-3925 2525);
WIRE 16 -1 (-4075 2525)(-4350 2525);
WIRE 16 -1 (-4350 2525)(-4725 2525);
WIRE 16 -1 (-4350 2650)(-4350 2525);
WIRE 16 -1 (-3525 2525)(-3925 2525);
WIRE 16 -1 (-3925 2650)(-3925 2525);
WIRE 16 -1 (-3100 2525)(-3525 2525);
WIRE 16 -1 (-3525 2650)(-3525 2525);
WIRE 16 -1 (-4725 2525)(-5150 2525);
WIRE 16 -1 (-4725 2650)(-4725 2525);
WIRE 16 -1 (-5150 2650)(-5150 2525);
WIRE 16 -1 (-3100 2650)(-3100 2525);
WIRE 16 -1 (-3750 1250)(-3750 1200);
WIRE 16 -1 (-3975 1250)(-3750 1250);
WIRE 16 -1 (-3600 1250)(-3750 1250);
WIRE 16 -1 (-3600 1375)(-3600 1250);
WIRE 16 -1 (-4350 1250)(-3975 1250);
WIRE 16 -1 (-3975 1375)(-3975 1250);
WIRE 16 -1 (-4775 1250)(-4350 1250);
WIRE 16 -1 (-4350 1375)(-4350 1250);
WIRE 16 -1 (-5200 1250)(-4775 1250);
WIRE 16 -1 (-4775 1375)(-4775 1250);
WIRE 16 -1 (-5200 1375)(-5200 1250);
WIRE 16 -1 (-4950 1650)(-4950 1700);
WIRE 16 -1 (-4950 1650)(-4775 1650);
WIRE 16 -1 (-5200 1650)(-4950 1650);
WIRE 16 -1 (-5200 1575)(-5200 1650);
WIRE 16 -1 (-4775 1650)(-4350 1650);
WIRE 16 -1 (-4775 1575)(-4775 1650);
WIRE 16 -1 (-4350 1650)(-3975 1650);
WIRE 16 -1 (-4350 1575)(-4350 1650);
WIRE 16 -1 (-3600 1650)(-3975 1650);
WIRE 16 -1 (-3975 1575)(-3975 1650);
WIRE 16 -1 (-3600 1575)(-3600 1650);
WIRE 16 -1 (-4325 5100)(-4325 5125);
WIRE 16 -1 (-4325 5100)(-4175 5100);
WIRE 16 -1 (-4575 5100)(-4325 5100);
WIRE 16 -1 (-4575 5025)(-4575 5100);
WIRE 16 -1 (-3775 5100)(-4175 5100);
WIRE 16 -1 (-4175 5025)(-4175 5100);
WIRE 16 -1 (-3375 5100)(-3775 5100);
WIRE 16 -1 (-3775 5025)(-3775 5100);
WIRE 16 -1 (-2975 5100)(-3375 5100);
WIRE 16 -1 (-3375 5025)(-3375 5100);
WIRE 16 -1 (-2550 5100)(-2975 5100);
WIRE 16 -1 (-2975 5025)(-2975 5100);
WIRE 16 -1 (-2550 5025)(-2550 5100);
WIRE 16 -1 (-4375 4100)(-4375 4200);
WIRE 16 -1 (-4375 4100)(-4200 4100);
WIRE 16 -1 (-4375 4100)(-4600 4100);
WIRE 16 -1 (-4600 4025)(-4600 4100);
WIRE 16 -1 (-3825 4100)(-4200 4100);
WIRE 16 -1 (-4200 4025)(-4200 4100);
WIRE 16 -1 (-3450 4100)(-3825 4100);
WIRE 16 -1 (-3825 4025)(-3825 4100);
WIRE 16 -1 (-3450 4025)(-3450 4100);
WIRE 16 -1 (-1475 4025)(-1475 4175);
WIRE 16 -1 (1125 5150)(1125 5103);
WIRE 16 -1 (1175 3650)(1175 3800);
WIRE 16 -1 (1175 4000)(1175 4125);
WIRE 16 -1 (650 2825)(650 2875);
WIRE 16 -1 (650 2825)(875 2825);
WIRE 16 -1 (425 2825)(650 2825);
WIRE 16 -1 (425 2750)(425 2825);
WIRE 16 -1 (1300 2825)(875 2825);
WIRE 16 -1 (875 2750)(875 2825);
WIRE 16 -1 (1300 2825)(1725 2825);
WIRE 16 -1 (1300 2825)(1300 2750);
WIRE 16 -1 (1725 2825)(1725 2750);
WIRE 16 -1 (1925 1700)(1925 1825);
WIRE 16 273 (-5250 5375)(-5250 3350);
WIRE 16 273 (700 5375)(-5250 5375);
WIRE 16 273 (700 5375)(700 3325);
WIRE 16 273 (-5250 3325)(700 3325);
WIRE 16 273 (-5275 3175)(-5275 950);
WIRE 16 273 (-5275 950)(-1350 950);
WIRE 16 273 (-1350 3175)(-5275 3175);
WIRE 16 273 (-1350 3175)(-1350 950);
WIRE 16 273 (275 3175)(275 950);
WIRE 16 273 (2475 3175)(275 3175);
WIRE 16 273 (2475 950)(275 950);
WIRE 16 273 (2475 950)(2475 3175);
WIRE 16 273 (806 3318)(2456 3318);
WIRE 16 273 (806 5393)(806 3318);
WIRE 16 273 (2456 5393)(2456 3318);
WIRE 16 273 (2456 5393)(806 5393);
WIRE 16 273 (-1250 3175)(-1250 950);
WIRE 16 273 (175 3175)(-1250 3175);
WIRE 16 273 (-1250 950)(175 950);
WIRE 16 273 (175 950)(175 3175);
WIRE 16 -1 (0 2125)(0 2275);
WIRE 16 -1 (-575 2275)(0 2275);
FORCEPROP 2 LAST SIG_NAME A_PVCCRTC_EXT_CAP
J 0
(-550 2285);
DISPLAY 0.617021 (-550 2285);
PAINT ORANGE (-550 2285);
DOT 1 (-4200 3700);
DOT 1 (1300 2425);
DOT 1 (-3775 4700);
DOT 1 (-3375 4700);
DOT 1 (-4325 4700);
DOT 1 (-4175 4700);
DOT 1 (-4775 1250);
DOT 1 (-4950 1650);
DOT 1 (-4775 1650);
DOT 1 (-4725 2525);
DOT 1 (-4350 1250);
DOT 1 (-3975 1250);
DOT 1 (-3750 1250);
DOT 1 (-4350 1650);
DOT 1 (-4350 2525);
DOT 1 (-4075 2525);
DOT 1 (-3975 1650);
DOT 1 (-3525 2525);
DOT 1 (-3925 2525);
DOT 1 (-4850 2925);
DOT 1 (-4725 2925);
DOT 1 (-4350 2925);
DOT 1 (-3925 2925);
DOT 1 (-3525 2925);
DOT 1 (-4375 3700);
DOT 1 (-4375 4100);
DOT 1 (-4200 4100);
DOT 1 (-3825 3700);
DOT 1 (-3825 4100);
DOT 1 (-4325 5100);
DOT 1 (-3775 5100);
DOT 1 (-3375 5100);
DOT 1 (-2975 4700);
DOT 1 (-2975 5100);
DOT 1 (650 2425);
DOT 1 (875 2425);
DOT 1 (650 2825);
DOT 1 (875 2825);
DOT 1 (1300 2825);
DOT 1 (-4175 5100);
FORCENOTE
ROOM=SB_DECOUPLING
(-5100 750) 0;
DISPLAY LEFT (-5100 750);
DISPLAY 2.148936 (-5100 750);
PAINT PURPLE (-5100 750);
FORCENOTE
BOM_COST=SB
(-3425 750) 0;
DISPLAY LEFT (-3425 750);
DISPLAY 2.148936 (-3425 750);
PAINT PURPLE (-3425 750);
QUIT
